G04 ================== begin FILE IDENTIFICATION RECORD ==================*
G04 Layout Name:  9052_F0T_PDB_Converter_Brick_F_V03_1208_1600.brd*
G04 Film Name:    bot*
G04 File Format:  Gerber RS274X*
G04 File Origin:  Cadence Allegro 17.2-S081*
G04 Origin Date:  Wed Dec 21 09:54:58 2022*
G04 *
G04 Layer:  DRAWING FORMAT/TITLE_BLOCK_A*
G04 Layer:  PIN/SPECIAL_DRILL*
G04 Layer:  DRAWING FORMAT/TITLE_BLOCK*
G04 Layer:  VIA CLASS/BOTTOM*
G04 Layer:  PIN/BOTTOM*
G04 Layer:  MANUFACTURING/PHOTOPLOT_OUTLINE*
G04 Layer:  ETCH/BOTTOM*
G04 Layer:  DRAWING FORMAT/TITLE_DATA_BOT*
G04 *
G04 Offset:    (0.00 0.00)*
G04 Mirror:    No*
G04 Mode:      Positive*
G04 Rotation:  0*
G04 FullContactRelief:  No*
G04 UndefLineWidth:     6.00*
G04 ================== end FILE IDENTIFICATION RECORD ====================*
%FSLAX25Y25*MOIN*%
%IR0*IPPOS*OFA0.00000B0.00000*MIA0B0*SFA1.00000B1.00000*%
%AMMACRO25*
4,1,8,.02953,-.06299,
-.02953,-.06299,
-.02953,.06299,
.02953,.06299,
.02953,.01968,
-.01771,.01968,
-.01771,-.01968,
.02953,-.01968,
.02953,-.06299,
0.0*
%
%ADD25MACRO25*%
%ADD10C,.02*%
%ADD13O,1.26X.394*%
%ADD67R,.13X.095*%
%ADD16C,.05*%
%AMMACRO12*
4,1,41,.45275,-.05906,
.463006,-.058163,
.47295,-.055498,
.48228,-.051147,
.490713,-.045243,
.497993,-.037963,
.503897,-.02953,
.508248,-.0202,
.510913,-.010256,
.51181,0.0,
.510913,.010256,
.508248,.0202,
.503897,.02953,
.497993,.037963,
.490713,.045243,
.48228,.051147,
.47295,.055498,
.463006,.058163,
.45275,.05906,
.33464,.05906,
-.4082,.09829,
-.425347,.097699,
-.442131,.09414,
-.458041,.08772,
-.472595,.078635,
-.485351,.06716,
-.49592,.053645,
-.503981,.0385,
-.509291,.022185,
-.511686,.005196,
-.511095,-.011951,
-.507536,-.028734,
-.501116,-.044645,
-.492031,-.059199,
-.480557,-.071954,
-.467041,-.082523,
-.451896,-.090585,
-.435582,-.095894,
-.418593,-.09829,
-.4082,-.09829,
.33464,-.05906,
.45275,-.05906,
0.0*
%
%ADD12MACRO12*%
%ADD41C,.06*%
%ADD34C,.052*%
%ADD32C,.062*%
%ADD19C,.026*%
%ADD27C,.018*%
%ADD58C,.066*%
%ADD45C,.06015*%
%ADD37C,.093*%
%ADD33C,.039*%
%ADD17R,.05X.05*%
%ADD50C,.085*%
%ADD42R,.06X.06*%
%ADD15C,.058*%
%ADD31R,.062X.062*%
%ADD14C,.087*%
%ADD57R,.066X.066*%
%ADD46R,.06015X.06015*%
%ADD44R,.093X.093*%
%AMMACRO40*
4,1,28,-.00748,.00052,
-.00984,.00052,
-.00984,.00603,
-.009782,.006705,
-.009607,.007359,
-.009321,.007974,
-.008933,.008529,
-.008455,.009009,
-.0079,.009398,
-.007286,.009685,
-.006632,.009861,
-.005957,.00992,
-.00591,.00992,
.00591,.00992,
.006585,.009869,
.007242,.009701,
.007859,.009421,
.008418,.009039,
.008903,.008565,
.009297,.008015,
.009591,.007404,
.009773,.006751,
.00984,.006077,
.00984,.00603,
.00984,.00052,
.00748,.00052,
.00748,-.00991,
-.00748,-.00991,
-.00748,.00052,
0.0*
%
%ADD40MACRO40*%
%AMMACRO23*
4,1,28,.00052,.00748,
.00052,.00984,
.00603,.00984,
.006705,.009782,
.007359,.009607,
.007974,.009321,
.008529,.008933,
.009009,.008455,
.009398,.0079,
.009685,.007286,
.009861,.006632,
.00992,.005957,
.00992,.00591,
.00992,-.00591,
.009869,-.006585,
.009701,-.007242,
.009421,-.007859,
.009039,-.008418,
.008565,-.008903,
.008015,-.009297,
.007404,-.009591,
.006751,-.009773,
.006077,-.00984,
.00603,-.00984,
.00052,-.00984,
.00052,-.00748,
-.00991,-.00748,
-.00991,.00748,
.00052,.00748,
0.0*
%
%ADD23MACRO23*%
%AMMACRO39*
4,1,28,-.00748,-.00051,
-.00984,-.00051,
-.00984,-.00602,
-.009782,-.006695,
-.009607,-.007349,
-.009321,-.007964,
-.008933,-.008519,
-.008455,-.008998,
-.0079,-.009388,
-.007287,-.009675,
-.006632,-.009851,
-.005958,-.00991,
-.00591,-.00991,
.00591,-.00991,
.006585,-.009859,
.007242,-.009691,
.007859,-.009411,
.008418,-.009029,
.008903,-.008555,
.009297,-.008005,
.00959,-.007394,
.009773,-.006742,
.00984,-.006068,
.00984,-.00602,
.00984,-.00051,
.00748,-.00051,
.00748,.00992,
-.00748,.00992,
-.00748,-.00051,
0.0*
%
%ADD39MACRO39*%
%AMMACRO22*
4,1,28,-.00051,.00748,
-.00051,.00984,
-.00602,.00984,
-.006695,.009782,
-.007349,.009607,
-.007964,.009321,
-.008519,.008933,
-.008998,.008455,
-.009388,.0079,
-.009675,.007287,
-.009851,.006632,
-.00991,.005958,
-.00991,.00591,
-.00991,-.00591,
-.009859,-.006585,
-.009691,-.007242,
-.009411,-.007859,
-.009029,-.008418,
-.008555,-.008903,
-.008005,-.009297,
-.007394,-.00959,
-.006742,-.009773,
-.006068,-.00984,
-.00602,-.00984,
-.00051,-.00984,
-.00051,-.00748,
.00992,-.00748,
.00992,.00748,
-.00051,.00748,
0.0*
%
%ADD22MACRO22*%
%ADD21R,.05X.04*%
%ADD43R,.02X.018*%
%ADD65R,.018X.02*%
%ADD64R,.034X.032*%
%AMMACRO26*
4,1,8,-.02953,.06299,
.02953,.06299,
.02953,-.06299,
-.02953,-.06299,
-.02953,-.01968,
.01771,-.01968,
.01771,.01968,
-.02953,.01968,
-.02953,.06299,
0.0*
%
%ADD26MACRO26*%
%ADD47R,.036X.032*%
%ADD63R,.032X.028*%
%ADD61R,.032X.036*%
%ADD52R,.017X.024*%
%ADD30C,.123*%
%ADD24R,.044X.016*%
%ADD62R,.028X.032*%
%ADD66R,.054X.026*%
%ADD56R,.014X.056*%
%ADD53R,.018X.052*%
%ADD48R,.054X.044*%
%ADD11C,.125*%
%ADD68C,.315*%
%ADD60R,.044X.054*%
%ADD55R,.062X.046*%
%ADD54R,.022X.068*%
%ADD51R,.014X.059*%
%ADD18C,.156*%
%ADD59R,.099X.067*%
%AMMACRO36*
4,1,28,.00748,-.00052,
.00984,-.00052,
.00984,-.00603,
.009782,-.006705,
.009607,-.007359,
.009321,-.007974,
.008933,-.008529,
.008455,-.009009,
.0079,-.009398,
.007286,-.009685,
.006632,-.009861,
.005957,-.00992,
.00591,-.00992,
-.00591,-.00992,
-.006585,-.009869,
-.007242,-.009701,
-.007859,-.009421,
-.008418,-.009039,
-.008903,-.008565,
-.009297,-.008015,
-.009591,-.007404,
-.009773,-.006751,
-.00984,-.006077,
-.00984,-.00603,
-.00984,-.00052,
-.00748,-.00052,
-.00748,.00991,
.00748,.00991,
.00748,-.00052,
0.0*
%
%ADD36MACRO36*%
%AMMACRO29*
4,1,28,-.00052,-.00748,
-.00052,-.00984,
-.00603,-.00984,
-.006705,-.009782,
-.007359,-.009607,
-.007974,-.009321,
-.008529,-.008933,
-.009009,-.008455,
-.009398,-.0079,
-.009685,-.007286,
-.009861,-.006632,
-.00992,-.005957,
-.00992,-.00591,
-.00992,.00591,
-.009869,.006585,
-.009701,.007242,
-.009421,.007859,
-.009039,.008418,
-.008565,.008903,
-.008015,.009297,
-.007404,.009591,
-.006751,.009773,
-.006077,.00984,
-.00603,.00984,
-.00052,.00984,
-.00052,.00748,
.00991,.00748,
.00991,-.00748,
-.00052,-.00748,
0.0*
%
%ADD29MACRO29*%
%AMMACRO35*
4,1,28,.00748,.00051,
.00984,.00051,
.00984,.00602,
.009782,.006695,
.009607,.007349,
.009321,.007964,
.008933,.008519,
.008455,.008998,
.0079,.009388,
.007287,.009675,
.006632,.009851,
.005958,.00991,
.00591,.00991,
-.00591,.00991,
-.006585,.009859,
-.007242,.009691,
-.007859,.009411,
-.008418,.009029,
-.008903,.008555,
-.009297,.008005,
-.00959,.007394,
-.009773,.006742,
-.00984,.006068,
-.00984,.00602,
-.00984,.00051,
-.00748,.00051,
-.00748,-.00992,
.00748,-.00992,
.00748,.00051,
0.0*
%
%ADD35MACRO35*%
%AMMACRO28*
4,1,28,.00051,-.00748,
.00051,-.00984,
.00602,-.00984,
.006695,-.009782,
.007349,-.009607,
.007964,-.009321,
.008519,-.008933,
.008998,-.008455,
.009388,-.0079,
.009675,-.007287,
.009851,-.006632,
.00991,-.005958,
.00991,-.00591,
.00991,.00591,
.009859,.006585,
.009691,.007242,
.009411,.007859,
.009029,.008418,
.008555,.008903,
.008005,.009297,
.007394,.00959,
.006742,.009773,
.006068,.00984,
.00602,.00984,
.00051,.00984,
.00051,.00748,
-.00992,.00748,
-.00992,-.00748,
.00051,-.00748,
0.0*
%
%ADD28MACRO28*%
%ADD69C,.01*%
%ADD70C,.04*%
%ADD71C,.014*%
%ADD72C,.015*%
%ADD73C,.016*%
%ADD74C,.025*%
%ADD75C,.017*%
%ADD76C,.035*%
%ADD77C,.006*%
%ADD78C,.0068*%
%ADD84C,.03004*%
%ADD79C,.07004*%
%ADD80C,.03604*%
%ADD90C,.14004*%
%ADD87C,.21204*%
%ADD88C,.13304*%
%ADD86C,.24304*%
%ADD92C,.40604*%
%ADD91C,.40408*%
%ADD89C,.33604*%
%ADD81C,.12806*%
%ADD82C,.16506*%
%ADD85C,.12709*%
%ADD83C,.28606*%
G75*
%LPD*%
G75*
G36*
G01X932200Y576740D02*
X1271654D01*
G02X1289339Y559055I0J-17685D01*
G01Y19685D01*
G02X1271654Y2000I-17685J0D01*
G01X19685D01*
G02X2000Y19685I0J17685D01*
G01Y40229D01*
G02X2176Y40427I200J-1D01*
G01X2647Y40483D01*
X2771Y40397D01*
X2789Y40322D01*
G03X3984Y36515I28708J6920D01*
G01X3998Y36480D01*
Y19685D01*
G03X19685Y3998I15687J0D01*
G01X1271654D01*
G03X1287341Y19685I0J15687D01*
G01Y559055D01*
G03X1271654Y574742I-15687J0D01*
G01X932200D01*
G02X932000Y574942I0J200D01*
G01Y576540D01*
G02X932200Y576740I200J0D01*
G37*
G36*
G01X11811Y73079D02*
X15720D01*
G02X15912Y72934I0J-200D01*
G01X16036Y72499D01*
X15988Y72375D01*
X15931Y72339D01*
G03X14119Y71120I15566J-25094D01*
G01X14093Y71101D01*
X14033Y71082D01*
X11811D01*
G03X3998Y63270I0J-7813D01*
G01Y58009D01*
X3984Y57974D01*
G03X2789Y54167I27513J-10727D01*
G01X2771Y54092D01*
X2647Y54006D01*
X2176Y54062D01*
G02X2000Y54260I24J199D01*
G01Y63268D01*
G02X11811Y73079I9811J0D01*
G37*
G36*
G01X41354Y457596D02*
X42832D01*
G02X43001Y457503I0J-200D01*
G01X43181Y457217D01*
G02X43194Y457025I-168J-108D01*
G02X37795Y453600I-5399J2543D01*
G01X11811D01*
G03X3998Y445787I0J-7813D01*
G01Y136102D01*
G03X11811Y128288I7814J0D01*
G01X37796D01*
G02X43761Y122323I-1J-5966D01*
G01X43762Y110392D01*
Y77047D01*
X43761D01*
Y76972D01*
G02X43561Y76774I-200J2D01*
G01X41963D01*
G02X41763Y76974I0J200D01*
G01Y76978D01*
G03X41764Y77047I-3967J92D01*
G01Y122323D01*
G03X37796Y126291I-3969J-1D01*
G01X11811D01*
G02X2000Y136102I0J9811D01*
G01Y445787D01*
G02X11811Y455598I9811J0D01*
G01X37795D01*
G03X41183Y457500I0J3968D01*
G02X41354Y457596I171J-104D01*
G37*
G36*
G01X2000Y518622D02*
Y528418D01*
G02X2176Y528616I200J-1D01*
G01X2647Y528672D01*
X2771Y528586D01*
X2789Y528511D01*
G03X3984Y524704I28708J6920D01*
G01X3998Y524669D01*
Y518622D01*
G03X11811Y510808I7814J0D01*
G01X15168D01*
X15224Y510791D01*
X15249Y510775D01*
G03X17260Y509561I16255J24654D01*
G01X17321Y509528D01*
X17375Y509403D01*
X17261Y508961D01*
G02X17067Y508811I-194J50D01*
G01X11811D01*
G02X2000Y518622I0J9811D01*
G37*
G36*
G01X19685Y576740D02*
X141800D01*
G02X142000Y576540I0J-200D01*
G01Y574942D01*
G02X141800Y574742I-200J0D01*
G01X19685D01*
G03X3998Y559055I0J-15687D01*
G01Y546198D01*
X3984Y546163D01*
G03X2789Y542356I27513J-10727D01*
G01X2771Y542281D01*
X2647Y542195D01*
X2176Y542251D01*
G02X2000Y542449I24J199D01*
G01Y559055D01*
G02X19685Y576740I17685J0D01*
G37*
G36*
G01X126400Y252300D02*
X132600Y258500D01*
X132500D01*
X136600Y262600D01*
X162800D01*
X166900Y258500D01*
X240417D01*
G03X240559Y258559I0J200D01*
G01X240741Y258741D01*
G02X240883Y258800I142J-141D01*
G01X244917D01*
G02X245059Y258741I0J-200D01*
G01X247839Y255961D01*
G02X247898Y255819I-141J-142D01*
G01Y172425D01*
G03X247949Y172292I200J0D01*
G01X247977Y172261D01*
X247990Y172222D01*
G02X248000Y172160I-190J-62D01*
G01Y168983D01*
G03X248059Y168841I200J0D01*
G01X252941Y163959D01*
G03X253083Y163900I142J141D01*
G01X378758D01*
G02X378900Y163841I0J-200D01*
G01X381041Y161700D01*
G02X381100Y161558I-141J-142D01*
G01Y11183D01*
G02X381041Y11041I-200J0D01*
G01X375959Y5959D01*
G02X375817Y5900I-142J141D01*
G01X16983D01*
G02X16841Y5959I0J200D01*
G01X6959Y15841D01*
G02X6900Y15983I141J142D01*
G01Y29628D01*
G02X7038Y29818I200J0D01*
G01X7400Y29935D01*
G02X7580Y29905I61J-190D01*
G01X7604Y29888D01*
X7623Y29863D01*
X7624Y29861D01*
G03X31496Y17714I23872J17384D01*
G01X118111D01*
G03X128536Y74873I0J29530D01*
G02X128502Y74889I68J189D01*
G02X128440Y74948I104J171D01*
G01X128400Y75008D01*
Y124244D01*
X128350Y124294D01*
X48223D01*
X47100Y125417D01*
G03X47041Y125559I-200J0D01*
G01X41359Y131241D01*
G03X41217Y131300I-142J-141D01*
G01X12583D01*
G02X12441Y131359I0J200D01*
G01X8859Y134941D01*
G02X8800Y135083I141J142D01*
G01Y257742D01*
X13216Y262158D01*
X93460D01*
X104705Y250913D01*
X105325Y250293D01*
X124393D01*
X125013Y250913D01*
X126400Y252300D01*
G37*
G36*
G01X130862Y407677D02*
Y412551D01*
X130834Y412579D01*
Y416506D01*
Y421202D01*
X130668Y421368D01*
Y427432D01*
X129600Y428500D01*
X113400D01*
X112900Y428000D01*
Y406700D01*
Y406000D01*
X113800Y405100D01*
X114500D01*
X130200D01*
X130862Y405762D01*
Y407677D01*
G37*
G36*
G01X149138Y421300D02*
Y416449D01*
Y412712D01*
X149261Y412589D01*
X149166Y412494D01*
Y407798D01*
Y405834D01*
X149900Y405100D01*
X165100D01*
X165800Y405800D01*
Y427500D01*
X165000Y428300D01*
X150100D01*
X149138Y427338D01*
Y421300D01*
G37*
G36*
G01X153583Y570869D02*
X874368D01*
G02X874510Y570810I0J-200D01*
G01X876941Y568379D01*
G02X877000Y568237I-141J-142D01*
G01Y567042D01*
G02X876817Y566843I-200J0D01*
G03Y550397I693J-8223D01*
G02X877000Y550198I-17J-199D01*
G01Y463483D01*
G02X876941Y463341I-200J0D01*
G01X874916Y461316D01*
G02X874774Y461257I-142J141D01*
G01X761891D01*
X761839Y461272D01*
X761815Y461286D01*
G03X761710Y461316I-105J-170D01*
G01X704946D01*
G02X704746Y461516I0J200D01*
G01Y462767D01*
G03X704546Y462966I-199J0D01*
G01X704510D01*
Y463810D01*
G03X704310Y464010I-200J0D01*
G01X704302D01*
G02X704102Y464210I0J200D01*
G01Y467828D01*
G02X704172Y467980I200J0D01*
G03X708413Y477204I-7910J9224D01*
G03X684109I-12152J0D01*
G03X688350Y467980I12151J0D01*
G02X688420Y467828I-130J-152D01*
G01Y464210D01*
G02X688220Y464010I-200J0D01*
G01X688212D01*
G03X688012Y463810I0J-200D01*
G01Y463466D01*
G02X687812Y463266I-200J0D01*
G01X609722D01*
G03X604605Y461365I2J-7842D01*
G01X604475Y461316D01*
X599355D01*
G02X599214Y461375I1J200D01*
G01X597808Y462780D01*
G02X597750Y462922I142J141D01*
G01X597662Y463010D01*
G02X597520Y463068I-1J200D01*
G01X597469Y463120D01*
G03X593329Y465290I-5545J-5545D01*
G02X593284Y465303I33J197D01*
G03X590076Y465977I-3191J-7216D01*
G01Y465976D01*
X588966D01*
Y465986D01*
X582968D01*
Y465987D01*
X574912D01*
G03X568676Y462930I1J-7892D01*
G01X566120D01*
G03X565700Y462942I-424J-7490D01*
G01X560300D01*
G03X555636Y461316I0J-7502D01*
G01X547466D01*
G02X547266Y461516I0J200D01*
G01Y462766D01*
G03X547066Y462966I-200J0D01*
G01X547030D01*
Y463810D01*
G03X546830Y464010I-200J0D01*
G01X546822D01*
G02X546622Y464209I-1J199D01*
G01Y467829D01*
X546691Y467980D01*
G03X550932Y477204I-7910J9224D01*
G03X526628I-12152J0D01*
G03X530869Y467980I12151J0D01*
G01X530938Y467829D01*
Y464209D01*
G02X530738Y464010I-199J0D01*
G01X530730D01*
G03X530530Y463810I0J-200D01*
G01Y463166D01*
G02X530330Y462966I-200J0D01*
G01X530294D01*
Y461516D01*
G02X530094Y461316I-200J0D01*
G01X440704D01*
G02X440504Y461516I0J200D01*
G01Y461767D01*
G03X440304Y461966I-199J-1D01*
G01X440268D01*
Y462810D01*
G03X440068Y463010I-200J0D01*
G01X438830D01*
X438750Y463047D01*
X438721Y463083D01*
G03X432595Y465977I-6107J-4996D01*
G01Y465976D01*
X431486D01*
Y465986D01*
X419752D01*
G03X419552Y465786I0J-201D01*
G01Y465750D01*
X418710D01*
G03X418510Y465550I0J-200D01*
G01Y464311D01*
X418472Y464231D01*
X418436Y464202D01*
G03X416282Y461431I4997J-6107D01*
G01X416101Y461316D01*
X389984D01*
G02X389784Y461516I0J200D01*
G01Y462767D01*
G03X389584Y462966I-200J0D01*
G01X389548D01*
Y463810D01*
G03X389348Y464010I-200J0D01*
G01X389340D01*
G02X389140Y464210I0J200D01*
G01Y467828D01*
G02X389210Y467980I200J0D01*
G03X393451Y477204I-7910J9224D01*
G03X369147I-12152J0D01*
G03X373388Y467980I12151J0D01*
G02X373458Y467828I-130J-152D01*
G01Y464210D01*
G02X373258Y464010I-200J0D01*
G01X373250D01*
G03X373050Y463810I0J-200D01*
G01Y463166D01*
G02X372850Y462966I-201J0D01*
G01X372814D01*
Y461516D01*
G02X372614Y461316I-200J0D01*
G01X232504D01*
G02X232304Y461516I0J200D01*
G01Y462767D01*
G03X232104Y462966I-199J0D01*
G01X232068D01*
Y463810D01*
G03X231868Y464010I-200J0D01*
G01X231860D01*
G02X231660Y464210I0J200D01*
G01Y467828D01*
G02X231730Y467980I200J0D01*
G03X235971Y477204I-7910J9224D01*
G03X211667I-12152J0D01*
G03X215908Y467980I12151J0D01*
G02X215978Y467828I-130J-152D01*
G01Y464210D01*
G02X215778Y464010I-200J0D01*
G01X215770D01*
G03X215570Y463810I0J-200D01*
G01Y463166D01*
G02X215370Y462966I-200J0D01*
G01X215334D01*
Y461516D01*
G02X215134Y461316I-200J0D01*
G01X149931D01*
X149857Y461346D01*
X149829Y461375D01*
X147822Y463381D01*
X147793Y463409D01*
X147763Y463483D01*
Y558041D01*
G02X147778Y558116I200J-1D01*
G01X147807Y558189D01*
G03X147822Y558265I-185J76D01*
G01Y565108D01*
G02X147881Y565250I200J0D01*
G01X153441Y570810D01*
G02X153583Y570869I142J-141D01*
G37*
G36*
G01X254883Y292700D02*
X304717D01*
G02X304859Y292641I0J-200D01*
G01X304941Y292559D01*
G03X305083Y292500I142J141D01*
G01X310917D01*
G02X311059Y292441I0J-200D01*
G01X314941Y288559D01*
G02X315000Y288417I-141J-142D01*
G01Y268083D01*
G03X315059Y267941I200J0D01*
G01X330082Y252918D01*
X691581D01*
X693413Y251086D01*
X703900D01*
X704933Y250053D01*
Y249040D01*
G03X704498Y247000I4567J-2040D01*
G01Y246998D01*
G03X704780Y245343I5002J1D01*
G01Y245208D01*
G03X704479Y243500I4701J-1709D01*
G03X707861Y238768I5001J0D01*
G01X707995Y238595D01*
G03X708191Y237558I4986J405D01*
G01X708200Y237500D01*
X708191Y237442D01*
G03X707979Y236002I4790J-1441D01*
G01Y236000D01*
G03X717983I5002J0D01*
G01Y236002D01*
G03X717771Y237442I-5002J-1D01*
G01X717762Y237500D01*
X717771Y237558D01*
G03X717983Y238998I-4790J1441D01*
G01Y239000D01*
G03X714601Y243732I-5001J0D01*
G01X714467Y243905D01*
G03X714201Y245157I-4986J-405D01*
G01Y245292D01*
G03X714502Y247000I-4701J1709D01*
G01Y247001D01*
G03X713994Y249197I-5002J0D01*
G01Y250274D01*
X714806Y251086D01*
X715095D01*
G03X716100Y250984I1005J4900D01*
G03X720051Y252918I0J5003D01*
G01X839798D01*
X840941Y251775D01*
G02X841000Y251633I-141J-142D01*
G01Y190023D01*
G02X840941Y189881I-200J0D01*
G01X838560Y187500D01*
G02X838419Y187442I-141J142D01*
G01X818100D01*
G03X815030Y186170I0J-4341D01*
G01X794730Y165870D01*
G03X793458Y162800I3069J-3070D01*
G01Y85541D01*
G02X793400Y85400I-200J0D01*
G01X787559Y79559D01*
G02X787417Y79500I-142J141D01*
G01X393783D01*
G02X393641Y79559I0J200D01*
G01X387259Y85941D01*
G02X387200Y86083I141J142D01*
G01Y161117D01*
G03X387141Y161259I-200J0D01*
G01X379159Y169241D01*
G03X379017Y169300I-142J-141D01*
G01X256683D01*
G02X256541Y169359I0J200D01*
G01X251959Y173941D01*
G02X251900Y174083I141J142D01*
G01Y262249D01*
G02X251963Y262394I200J-1D01*
G03X253507Y264597I-4521J4811D01*
G01X253528Y264648D01*
G03X254043Y267204I-6087J2556D01*
G03X253429Y269984I-6602J0D01*
G01X253407Y270031D01*
X253414Y270132D01*
X253652Y270504D01*
X253742Y270552D01*
X253819D01*
G03Y283856I0J6652D01*
G03X249652Y282389I0J-6652D01*
G01X249607Y282353D01*
X249493Y282340D01*
X249116Y282521D01*
G02X249002Y282701I86J181D01*
G01Y286819D01*
G02X249060Y286960I200J0D01*
G01X254741Y292641D01*
G02X254883Y292700I142J-141D01*
G37*
G36*
G01X248220Y273613D02*
G03X253819Y270552I5600J3592D01*
G03X258511Y272489I0J6651D01*
G01X263000Y268000D01*
Y262000D01*
X261000Y260000D01*
X253100D01*
X252200Y260900D01*
Y266549D01*
X251545Y267204D01*
G03X247920Y271280I-4104J0D01*
G01X246900Y272300D01*
Y273200D01*
X247313Y273613D01*
X248220D01*
G37*
G36*
G01X560432Y448192D02*
X565514D01*
X565928Y447778D01*
Y441157D01*
X565515Y440744D01*
X560639D01*
X560195Y441188D01*
Y447955D01*
X560432Y448192D01*
G37*
G36*
G01X642367Y41150D02*
X637233D01*
G02X637091Y41209I0J200D01*
G01X636759Y41541D01*
G02X636700Y41683I141J142D01*
G01Y48717D01*
G02X636759Y48859I200J0D01*
G01X637441Y49541D01*
G02X637583Y49600I142J-141D01*
G01X642117D01*
G02X642259Y49541I0J-200D01*
G01X642841Y48959D01*
G02X642900Y48817I-141J-142D01*
G01Y41683D01*
G02X642841Y41541I-200J0D01*
G01X642509Y41209D01*
G02X642367Y41150I-142J141D01*
G37*
G36*
G01X698650Y66067D02*
Y48133D01*
G02X698591Y47991I-200J0D01*
G01X697659Y47059D01*
G02X697517Y47000I-142J141D01*
G01X651683D01*
G02X651541Y47059I0J200D01*
G01X650459Y48141D01*
G02X650400Y48283I141J142D01*
G01Y65517D01*
G02X650459Y65659I200J0D01*
G01X651541Y66741D01*
G02X651683Y66800I142J-141D01*
G01X697917D01*
G02X698059Y66741I0J-200D01*
G01X698591Y66209D01*
G02X698650Y66067I-141J-142D01*
G37*
G36*
G01X729126Y71416D02*
X730948Y73238D01*
G02X731090Y73297I142J-141D01*
G01X750061D01*
X752203D01*
X754000Y71500D01*
Y26000D01*
X753000Y25000D01*
X731194D01*
X730488Y25706D01*
X730487Y25707D01*
X729126Y27068D01*
G02X729067Y27210I141J142D01*
G01Y71274D01*
G02X729126Y71416I200J0D01*
G37*
G36*
G01X732708Y332400D02*
G03I-608J0D01*
G37*
G36*
G01X754884Y71366D02*
Y26134D01*
X755932Y25086D01*
X762479D01*
X763526Y26133D01*
Y71396D01*
X762240Y72682D01*
X756200D01*
X754884Y71366D01*
G37*
G36*
G01X1063022Y566219D02*
X1081224D01*
G02X1081366Y566160I0J-200D01*
G01X1082543Y564983D01*
G02X1082602Y564841I-141J-142D01*
G01Y428102D01*
X1078242Y423742D01*
X1060984D01*
G03X1057903Y414804I0J-5000D01*
G01X1071107Y401600D01*
X1081800D01*
X1082043Y401357D01*
Y379243D01*
X1081318Y378518D01*
G03X1080420Y378600I-902J-4918D01*
G01X1080418D01*
G03X1075418Y373600I0J-5000D01*
G01Y372618D01*
X1073300Y370500D01*
X1067000D01*
X1066872Y370372D01*
G03X1062777Y366277I835J-4930D01*
G01X1061119Y364619D01*
G03X1056600Y359642I481J-4977D01*
G03X1060671Y354729I5000J0D01*
G01X1061300Y354100D01*
X1081800D01*
X1082043Y353857D01*
Y334957D01*
X1082602Y334398D01*
Y241385D01*
G02X1082543Y241243I-200J0D01*
G01X1039206Y197906D01*
X1039133Y197876D01*
X1039092Y197877D01*
X1039016D01*
G03X1030214Y189075I0J-8802D01*
G01Y188999D01*
X1030215Y188915D01*
X1030200Y188900D01*
Y181783D01*
G02X1030141Y181641I-200J0D01*
G01X1028959Y180459D01*
G02X1028817Y180400I-142J141D01*
G01X1015183D01*
G02X1015041Y180459I0J200D01*
G01X1013359Y182141D01*
G02X1013300Y182283I141J142D01*
G01Y211911D01*
G02X1013332Y212019I200J0D01*
G03X988500Y257530I-24832J15981D01*
G01X966352D01*
G02X966211Y257589I1J200D01*
G01X962059Y261741D01*
G02X962000Y261883I141J142D01*
G01Y375444D01*
G03X961957Y375543I-6902J-2939D01*
G01X958200Y379300D01*
X837980D01*
X833178Y384102D01*
X776000D01*
X772000Y388102D01*
Y451500D01*
X774000Y453500D01*
X880117D01*
G03X880259Y453559I0J200D01*
G01X882941Y456241D01*
G03X883000Y456383I-141J142D01*
G01Y528917D01*
G02X883059Y529059I200J0D01*
G01X885441Y531441D01*
G02X885583Y531500I142J-141D01*
G01X912417D01*
G02X912559Y531441I0J-200D01*
G01X931441Y512559D01*
G03X931583Y512500I142J141D01*
G01X1043417D01*
G03X1043559Y512559I0J200D01*
G01X1060441Y529441D01*
G03X1060500Y529583I-141J142D01*
G01Y563697D01*
G02X1060559Y563839I200J0D01*
G01X1062880Y566160D01*
G02X1063022Y566219I142J-141D01*
G37*
G36*
G01X845740Y373000D02*
X954017D01*
X954950D01*
X955630Y372320D01*
Y365110D01*
X954720Y364200D01*
X845560D01*
X845020Y364740D01*
Y372280D01*
X845740Y373000D01*
G37*
G36*
G01X1040583Y152300D02*
X1042617D01*
G02X1042759Y152241I0J-200D01*
G01X1043041Y151959D01*
G02X1043100Y151817I-141J-142D01*
G01Y150183D01*
G03X1043159Y150041I200J0D01*
G01X1047241Y145959D01*
G02X1047300Y145817I-141J-142D01*
G01Y143783D01*
G02X1047241Y143641I-200J0D01*
G01X1046372Y142772D01*
G02X1046340Y142746I-141J141D01*
G03X1045900Y142306I819J-1259D01*
G01X1045889Y142289D01*
X1045659Y142059D01*
G03X1045600Y141917I141J-142D01*
G01Y140383D01*
G03X1045659Y140241I200J0D01*
G01X1046346Y139554D01*
X1046446D01*
X1047508Y138492D01*
Y124708D01*
X1047300Y124500D01*
X1038800D01*
X1036500Y126800D01*
Y142651D01*
X1036906Y143057D01*
X1036957D01*
X1038641Y144741D01*
G03X1038700Y144883I-141J142D01*
G01Y150417D01*
G02X1038759Y150559I200J0D01*
G01X1040441Y152241D01*
G02X1040583Y152300I142J-141D01*
G37*
G36*
G01X1062000Y127000D02*
X1069000D01*
X1071000D01*
X1071500Y126500D01*
Y122500D01*
X1071000Y122000D01*
X1062000D01*
X1061500Y122500D01*
Y126500D01*
X1062000Y127000D01*
G37*
G36*
G01X1179823Y120652D02*
G03X1179614Y121416I-1503J0D01*
G02X1179596Y121579I172J102D01*
G03X1180002Y124150I-7945J2572D01*
G01Y135340D01*
G02X1180202Y135540I200J0D01*
G01X1193674D01*
G03X1193816Y135599I0J200D01*
G01X1199765Y141548D01*
G03X1199824Y141690I-141J142D01*
G01Y195831D01*
G02X1199883Y195973I200J0D01*
G01X1218910Y215000D01*
G03X1218969Y215142I-141J142D01*
G01Y215575D01*
G02X1219027Y215717I200J1D01*
G01X1219205Y215895D01*
G03X1221652Y221800I-5904J5906D01*
G01Y270663D01*
G02X1221711Y270805I200J0D01*
G01X1223536Y272630D01*
G02X1223678Y272689I142J-141D01*
G01X1256952D01*
G02X1257094Y272630I0J-200D01*
G01X1272241Y257483D01*
G02X1272300Y257341I-141J-142D01*
G01Y25487D01*
G02X1272241Y25345I-200J0D01*
G01X1263741Y16845D01*
G02X1263599Y16786I-142J141D01*
G01X1096887D01*
G02X1096745Y16845I0J200D01*
G01X1095467Y18123D01*
G02X1095408Y18265I141J142D01*
G01Y58039D01*
G02X1095467Y58181I200J0D01*
G01X1117273Y79987D01*
G02X1117415Y80046I142J-141D01*
G01X1122650D01*
G03X1122792Y80105I0J200D01*
G01X1129646Y86959D01*
G02X1129711Y87002I141J-142D01*
G01X1132399Y88116D01*
G02X1132476Y88131I76J-185D01*
G01X1142376D01*
G02X1142518Y88072I0J-200D01*
G01X1144931Y85659D01*
G03X1145073Y85600I142J141D01*
G01X1172634D01*
G03X1172776Y85659I0J200D01*
G01X1174941Y87824D01*
G03X1175000Y87966I-141J142D01*
G01Y115606D01*
G02X1175059Y115748I200J0D01*
G01X1177555Y118245D01*
G03X1178283Y119076I-5904J5907D01*
G02X1178427Y119154I159J-122D01*
G03X1179823Y120652I-106J1498D01*
G37*
G36*
G01X1081500Y138000D02*
X1085660D01*
X1085960Y137700D01*
Y131140D01*
X1086500Y130600D01*
Y129500D01*
X1086000Y129000D01*
X1081000D01*
X1080500Y129500D01*
Y137000D01*
X1081500Y138000D01*
G37*
G36*
G01X1114223Y217338D02*
X1122328D01*
X1122552Y217114D01*
Y211500D01*
X1113105Y202053D01*
X1096890D01*
X1096376Y202567D01*
Y204893D01*
X1108821Y217338D01*
X1114223D01*
G37*
G36*
G01X1100938Y376748D02*
X1173569D01*
G02X1173711Y376689I0J-200D01*
G01X1176841Y373559D01*
G02X1176900Y373417I-141J-142D01*
G01Y350882D01*
G02X1176813Y350718I-200J1D01*
G03Y347750I1024J-1484D01*
G02X1176900Y347586I-113J-165D01*
G01Y329181D01*
G02X1176777Y328996I-200J0D01*
G01X1176720Y328972D01*
X1176602Y328996D01*
X1175504Y330095D01*
G03X1174159Y330652I-1345J-1345D01*
G01X1165070D01*
G03Y326848I0J-1902D01*
G01X1173289D01*
G02X1173430Y326790I0J-200D01*
G01X1176841Y323378D01*
G02X1176900Y323237I-141J-142D01*
G01Y242983D01*
G02X1176841Y242841I-200J0D01*
G01X1173559Y239559D01*
G02X1173417Y239500I-142J141D01*
G01X1100549D01*
G02X1100407Y239559I0J200D01*
G01X1098479Y241487D01*
G02X1098420Y241629I141J142D01*
G01Y332700D01*
G02X1098473Y332835I200J-1D01*
G03X1100802Y338800I-6474J5965D01*
G03X1100653Y340411I-8802J-2D01*
G02X1100656Y340498I197J37D01*
G03X1100902Y342400I-7256J1905D01*
G01Y345600D01*
G03X1100814Y346745I-7502J-1D01*
G02X1100893Y346937I197J31D01*
G03X1103977Y353000I-4418J6063D01*
G01Y355000D01*
Y355085D01*
X1103976Y355087D01*
Y356015D01*
X1103985Y356044D01*
G03X1104377Y358640I-8410J2597D01*
G03X1104328Y359571I-8802J4D01*
G01X1104326Y359582D01*
Y361811D01*
G03X1102263Y367455I-8752J0D01*
G02X1102217Y367601I153J129D01*
G03X1102244Y368243I-7474J636D01*
G01Y371443D01*
G03X1100624Y376100I-7501J1D01*
G01X1100588Y376146D01*
X1100575Y376258D01*
X1100758Y376635D01*
G02X1100938Y376748I180J-87D01*
G37*
G36*
G01X1079432Y360500D02*
X1083785D01*
X1084552Y361267D01*
X1089233D01*
X1093500Y357000D01*
Y350000D01*
Y348300D01*
X1093400Y348200D01*
X1090600D01*
X1090350Y348450D01*
Y349550D01*
X1089000Y350900D01*
X1084734D01*
X1084534Y351100D01*
Y352671D01*
Y357682D01*
X1083748Y358468D01*
X1083184D01*
X1079400D01*
X1079298Y358570D01*
Y360366D01*
X1079432Y360500D01*
G37*
G36*
G01X1084700Y345500D02*
X1089000D01*
X1090400D01*
X1090600Y345700D01*
X1093400D01*
X1093500Y345600D01*
Y342500D01*
X1093400Y342400D01*
X1084800D01*
X1084600Y342600D01*
Y345400D01*
X1084700Y345500D01*
G37*
G36*
G01Y394000D02*
X1088000D01*
X1088800Y393200D01*
X1092500D01*
X1092700Y393000D01*
Y390200D01*
X1092500Y390000D01*
X1085700D01*
X1084600Y391100D01*
Y393900D01*
X1084700Y394000D01*
G37*
G36*
G01X1084552Y408767D02*
X1089233D01*
X1093500Y404500D01*
Y396900D01*
X1092400Y395800D01*
X1089600D01*
X1087000Y398400D01*
X1084734D01*
X1084643Y398491D01*
Y402457D01*
X1084534Y402566D01*
Y405182D01*
X1083748Y405968D01*
X1079400D01*
X1079298Y406070D01*
Y407998D01*
X1079400Y408100D01*
X1083885D01*
X1084552Y408767D01*
G37*
G36*
G01X1099441Y527259D02*
X1097559Y529141D01*
G02X1097500Y529283I141J142D01*
G01Y566117D01*
G02X1097559Y566259I200J0D01*
G01X1099841Y568541D01*
G02X1099983Y568600I142J-141D01*
G01X1125017D01*
G02X1125159Y568541I0J-200D01*
G01X1128041Y565659D01*
G02X1128100Y565517I-141J-142D01*
G01Y529383D01*
G02X1128041Y529241I-200J0D01*
G01X1126059Y527259D01*
G02X1125917Y527200I-142J141D01*
G01X1099583D01*
G02X1099441Y527259I0J200D01*
G37*
G36*
G01X1108600Y128100D02*
X1116953D01*
X1117409Y127644D01*
Y123615D01*
X1116294Y122500D01*
X1114900D01*
X1107800D01*
X1107700Y122600D01*
Y127200D01*
X1108600Y128100D01*
G37*
G36*
G01X1186427Y479133D02*
X1257784D01*
G02X1257926Y479074I0J-200D01*
G01X1261441Y475559D01*
G02X1261500Y475417I-141J-142D01*
G01Y303500D01*
X1260050Y302050D01*
X1258559Y300559D01*
G02X1258417Y300500I-142J141D01*
G01X1214424D01*
G03X1214282Y300441I0J-200D01*
G01X1204559Y290718D01*
G03X1204500Y290576I141J-142D01*
G01Y226400D01*
X1189600Y211500D01*
X1181600Y203500D01*
X1166500D01*
X1165000Y205000D01*
Y209000D01*
X1162500Y211500D01*
X1158500D01*
X1125730D01*
X1125350Y211880D01*
Y226450D01*
X1126700Y227800D01*
X1175200D01*
X1184402Y237002D01*
Y318820D01*
X1184502D01*
Y322010D01*
G02X1184561Y322152I200J0D01*
G01X1189199Y326789D01*
G02X1189341Y326848I142J-141D01*
G01X1193411D01*
G03Y330652I0J1902D01*
G01X1185200D01*
X1184502Y331350D01*
Y334300D01*
X1184402D01*
Y366320D01*
X1184502D01*
Y464360D01*
G02X1184561Y464502I200J0D01*
G01X1189349Y469289D01*
G02X1189491Y469348I142J-141D01*
G01X1193840D01*
G03Y473152I0J1902D01*
G01X1185000D01*
X1184502Y473650D01*
Y477291D01*
X1186285Y479074D01*
G02X1186427Y479133I142J-141D01*
G37*
G36*
G01X1105383Y488500D02*
X1158817D01*
G02X1158959Y488441I0J-200D01*
G01X1163041Y484359D01*
G02X1163100Y484217I-141J-142D01*
G01Y470133D01*
G03X1163159Y469991I200J0D01*
G01X1164738Y468412D01*
G03X1164888Y468354I141J142D01*
G01X1171513D01*
G02X1171655Y468295I0J-200D01*
G01X1176941Y463009D01*
G02X1177000Y462867I-141J-142D01*
G01Y383583D01*
G02X1176941Y383441I-200J0D01*
G01X1175559Y382059D01*
G02X1175417Y382000I-142J141D01*
G01X1105583D01*
G02X1105441Y382059I0J200D01*
G01X1102359Y385141D01*
G02X1102300Y385283I141J142D01*
G01Y395703D01*
G02X1102344Y395827I200J-1D01*
G03X1103976Y400500I-5870J4671D01*
G01Y403685D01*
X1103985Y403714D01*
G03X1104377Y406310I-8410J2597D01*
G03X1104328Y407241I-8802J4D01*
G01X1104326Y407252D01*
Y409311D01*
G03X1102345Y414856I-8751J0D01*
G02X1102300Y414983I155J126D01*
G01Y485417D01*
G02X1102359Y485559I200J0D01*
G01X1105241Y488441D01*
G02X1105383Y488500I142J-141D01*
G37*
G36*
G01X1154500Y182500D02*
X1158000D01*
X1159500Y181000D01*
Y179000D01*
X1157000Y176500D01*
Y174700D01*
X1156300Y174000D01*
X1152500D01*
X1152000Y174500D01*
Y180000D01*
X1154500Y182500D01*
G37*
G36*
G01X1176681Y182898D02*
X1189915D01*
G02X1190057Y182840I1J-200D01*
G01X1190391Y182506D01*
G02X1190450Y182364I-141J-142D01*
G01Y151733D01*
G02X1190391Y151591I-200J0D01*
G01X1190209Y151409D01*
G02X1190067Y151350I-142J141D01*
G01X1176933D01*
G02X1176791Y151409I0J200D01*
G01X1176259Y151941D01*
G02X1176200Y152083I141J142D01*
G01Y182417D01*
G02X1176259Y182559I200J0D01*
G01X1176539Y182839D01*
G02X1176681Y182898I142J-141D01*
G37*
%LPC*%
G75*
G36*
G01X139000Y235300D02*
X141300Y237600D01*
X155100D01*
X157266Y235434D01*
X161478D01*
G02X162850Y235630I1372J-4707D01*
G01X162853D01*
G02X164051Y235481I-1J-4902D01*
G03X164149I49J194D01*
G02X165347Y235630I1199J-4753D01*
G01X165350D01*
G02X166722Y235434I0J-4902D01*
G01X169766D01*
X170700Y234500D01*
Y217800D01*
X172500Y216000D01*
X180600D01*
X182200Y214400D01*
X202300D01*
X205500Y211200D01*
Y202100D01*
X203200Y199800D01*
X192600D01*
X184700Y191900D01*
X174000D01*
X159300Y206600D01*
Y211500D01*
X155500Y215300D01*
X141400D01*
X139000Y217700D01*
Y235300D01*
G37*
G36*
G01X176535Y233067D02*
Y233068D01*
G02X178329Y234702I1794J-168D01*
G02X180131Y232900I0J-1802D01*
G02X179716Y231750I-1802J0D01*
G03X179670Y231623I154J-128D01*
G01Y229425D01*
G03X179870Y229225I200J0D01*
G01X182379D01*
G02X182698Y229110I-1J-502D01*
G01X182699Y229109D01*
G03X182825Y229064I126J155D01*
G01X184317D01*
G02X185263Y228672I-2J-1342D01*
G01X185999Y227935D01*
G03X186121Y227877I142J141D01*
G01X186122D01*
G02Y224289I-168J-1794D01*
G01X186121D01*
G03X185999Y224231I20J-199D01*
G01X184343Y222574D01*
G02X183397Y222182I-948J950D01*
G01X182760D01*
X182695Y222158D01*
X182668Y222136D01*
G02X182350Y222022I-318J387D01*
G01X180549D01*
G02X180115Y222272I0J502D01*
G01X179863D01*
Y224774D01*
X180115D01*
G02X180549Y225024I434J-252D01*
G01X182351D01*
G02X182668Y224910I-1J-501D01*
G03X182795Y224864I128J154D01*
G01X182838D01*
X183916Y225942D01*
G03Y226224I-142J141D01*
G01X183817Y226323D01*
G03X183675Y226382I-142J-141D01*
G01X182825D01*
G03X182699Y226337I0J-200D01*
G01X182698Y226336D01*
G02X182379Y226221I-320J387D01*
G01X178030D01*
G03X177832Y226045I1J-200D01*
G01Y226044D01*
G02X177449Y225253I-1332J157D01*
G01X176908Y224713D01*
X176893Y224671D01*
G02X175481Y223681I-1412J512D01*
G02X173979Y225183I0J1502D01*
G01Y225185D01*
G02X174113Y225804I1502J-1D01*
G01X174134Y225849D01*
X174128Y225948D01*
X173931Y226273D01*
G03X173771Y226369I-171J-104D01*
G02X172067Y228168I98J1799D01*
G02X173869Y229970I1802J0D01*
G02X174596Y229816I-2J-1802D01*
G01X174598D01*
X174644Y229796D01*
X174744Y229804D01*
X175067Y230015D01*
G03X175158Y230182I-109J168D01*
G01Y231071D01*
G02X175551Y232020I1342J0D01*
G01X176477Y232945D01*
G03X176535Y233067I-141J142D01*
G37*
G36*
G01X167917Y252423D02*
G02X169839Y252807I1922J-4618D01*
G01X169840D01*
G02Y242803I0J-5002D01*
G01X169839D01*
G02X167917Y243187I0J5002D01*
G03X167763I-77J-184D01*
G02X165841Y242803I-1922J4618D01*
G01X165840D01*
G02Y252807I0J5002D01*
G01X165841D01*
G02X167763Y252423I0J-5002D01*
G03X167917I77J184D01*
G37*
G36*
G01X248668Y481856D02*
G02X249169Y482356I501J-1D01*
G01X258469D01*
G02X258970Y481854I-1J-502D01*
G01Y472552D01*
G02X258469Y472052I-501J1D01*
G01X249169D01*
G02X248668Y472554I1J502D01*
G01Y481856D01*
G37*
G36*
G01X406148D02*
G02X406649Y482356I501J-1D01*
G01X415949D01*
G02X416450Y481854I-1J-502D01*
G01Y472552D01*
G02X415949Y472052I-501J1D01*
G01X406649D01*
G02X406148Y472554I1J502D01*
G01Y481856D01*
G37*
G36*
G01X563628Y481854D02*
G02X564130Y482356I502J0D01*
G01X573430D01*
G02X573932Y481854I0J-502D01*
G01Y472554D01*
G02X573430Y472052I-502J0D01*
G01X564130D01*
G02X563628Y472554I0J502D01*
G01Y481854D01*
G37*
G36*
G01X721110Y481856D02*
G02X721611Y482356I501J-1D01*
G01X730911D01*
G02X731412Y481854I-1J-502D01*
G01Y472552D01*
G02X730911Y472052I-501J1D01*
G01X721611D01*
G02X721110Y472554I1J502D01*
G01Y481856D01*
G37*
G36*
G01X181140Y506481D02*
G03X181207Y506487I16J199D01*
G02X183539Y506802I2334J-8487D01*
G02Y489198I0J-8802D01*
G02X181207Y489513I2J8802D01*
G03X181140Y489519I-51J-193D01*
G02X180547Y489498I-597J8481D01*
G01X180539D01*
G02Y506502I0J8502D01*
G01X180547D01*
G02X181140Y506481I-4J-8502D01*
G37*
G36*
G01X229140D02*
G03X229207Y506487I16J199D01*
G02X231539Y506802I2334J-8487D01*
G02Y489198I0J-8802D01*
G02X229207Y489513I2J8802D01*
G03X229140Y489519I-51J-193D01*
G02X228547Y489498I-597J8481D01*
G01X228539D01*
G02Y506502I0J8502D01*
G01X228547D01*
G02X229140Y506481I-4J-8502D01*
G37*
G36*
G01X277140D02*
G03X277207Y506487I16J199D01*
G02X279539Y506802I2334J-8487D01*
G02Y489198I0J-8802D01*
G02X277207Y489513I2J8802D01*
G03X277140Y489519I-51J-193D01*
G02X276547Y489498I-597J8481D01*
G01X276539D01*
G02Y506502I0J8502D01*
G01X276547D01*
G02X277140Y506481I-4J-8502D01*
G37*
G36*
G01X338620D02*
G03X338687Y506487I16J199D01*
G02X341019Y506802I2334J-8487D01*
G02Y489198I0J-8802D01*
G02X338687Y489513I2J8802D01*
G03X338620Y489519I-51J-193D01*
G02X338027Y489498I-597J8481D01*
G01X338019D01*
G02Y506502I0J8502D01*
G01X338027D01*
G02X338620Y506481I-4J-8502D01*
G37*
G36*
G01X386620D02*
G03X386687Y506487I16J199D01*
G02X389019Y506802I2334J-8487D01*
G02Y489198I0J-8802D01*
G02X386687Y489513I2J8802D01*
G03X386620Y489519I-51J-193D01*
G02X386027Y489498I-597J8481D01*
G01X386019D01*
G02Y506502I0J8502D01*
G01X386027D01*
G02X386620Y506481I-4J-8502D01*
G37*
G36*
G01X434620D02*
G03X434687Y506487I16J199D01*
G02X437019Y506802I2334J-8487D01*
G02Y489198I0J-8802D01*
G02X434687Y489513I2J8802D01*
G03X434620Y489519I-51J-193D01*
G02X434027Y489498I-597J8481D01*
G01X434019D01*
G02Y506502I0J8502D01*
G01X434027D01*
G02X434620Y506481I-4J-8502D01*
G37*
G36*
G01X496101D02*
G03X496168Y506487I16J199D01*
G02X498500Y506802I2334J-8487D01*
G02Y489198I0J-8802D01*
G02X496168Y489513I2J8802D01*
G03X496101Y489519I-51J-193D01*
G02X495508Y489498I-597J8481D01*
G01X495500D01*
G02Y506502I0J8502D01*
G01X495508D01*
G02X496101Y506481I-4J-8502D01*
G37*
G36*
G01X544101D02*
G03X544168Y506487I16J199D01*
G02X546500Y506802I2334J-8487D01*
G02Y489198I0J-8802D01*
G02X544168Y489513I2J8802D01*
G03X544101Y489519I-51J-193D01*
G02X543508Y489498I-597J8481D01*
G01X543500D01*
G02Y506502I0J8502D01*
G01X543508D01*
G02X544101Y506481I-4J-8502D01*
G37*
G36*
G01X592101D02*
G03X592168Y506487I16J199D01*
G02X594500Y506802I2334J-8487D01*
G02Y489198I0J-8802D01*
G02X592168Y489513I2J8802D01*
G03X592101Y489519I-51J-193D01*
G02X591508Y489498I-597J8481D01*
G01X591500D01*
G02Y506502I0J8502D01*
G01X591508D01*
G02X592101Y506481I-4J-8502D01*
G37*
G36*
G01X653582D02*
G03X653649Y506487I16J199D01*
G02X655981Y506802I2334J-8487D01*
G02Y489198I0J-8802D01*
G02X653649Y489513I2J8802D01*
G03X653582Y489519I-51J-193D01*
G02X652989Y489498I-597J8481D01*
G01X652981D01*
G02Y506502I0J8502D01*
G01X652989D01*
G02X653582Y506481I-4J-8502D01*
G37*
G36*
G01X701582D02*
G03X701649Y506487I16J199D01*
G02X703981Y506802I2334J-8487D01*
G02Y489198I0J-8802D01*
G02X701649Y489513I2J8802D01*
G03X701582Y489519I-51J-193D01*
G02X700989Y489498I-597J8481D01*
G01X700981D01*
G02Y506502I0J8502D01*
G01X700989D01*
G02X701582Y506481I-4J-8502D01*
G37*
G36*
G01X749582D02*
G03X749649Y506487I16J199D01*
G02X751981Y506802I2334J-8487D01*
G02Y489198I0J-8802D01*
G02X749649Y489513I2J8802D01*
G03X749582Y489519I-51J-193D01*
G02X748989Y489498I-597J8481D01*
G01X748981D01*
G02Y506502I0J8502D01*
G01X748989D01*
G02X749582Y506481I-4J-8502D01*
G37*
G36*
G01X181140Y526481D02*
G03X181207Y526487I16J199D01*
G02X183539Y526802I2334J-8487D01*
G02Y509198I0J-8802D01*
G02X181207Y509513I2J8802D01*
G03X181140Y509519I-51J-193D01*
G02X180547Y509498I-597J8481D01*
G01X180539D01*
G02Y526502I0J8502D01*
G01X180547D01*
G02X181140Y526481I-4J-8502D01*
G37*
G36*
G01X229140D02*
G03X229207Y526487I16J199D01*
G02X231539Y526802I2334J-8487D01*
G02Y509198I0J-8802D01*
G02X229207Y509513I2J8802D01*
G03X229140Y509519I-51J-193D01*
G02X228547Y509498I-597J8481D01*
G01X228539D01*
G02Y526502I0J8502D01*
G01X228547D01*
G02X229140Y526481I-4J-8502D01*
G37*
G36*
G01X277140D02*
G03X277207Y526487I16J199D01*
G02X279539Y526802I2334J-8487D01*
G02Y509198I0J-8802D01*
G02X277207Y509513I2J8802D01*
G03X277140Y509519I-51J-193D01*
G02X276547Y509498I-597J8481D01*
G01X276539D01*
G02Y526502I0J8502D01*
G01X276547D01*
G02X277140Y526481I-4J-8502D01*
G37*
G36*
G01X338620D02*
G03X338687Y526487I16J199D01*
G02X341019Y526802I2334J-8487D01*
G02Y509198I0J-8802D01*
G02X338687Y509513I2J8802D01*
G03X338620Y509519I-51J-193D01*
G02X338027Y509498I-597J8481D01*
G01X338019D01*
G02Y526502I0J8502D01*
G01X338027D01*
G02X338620Y526481I-4J-8502D01*
G37*
G36*
G01X386620D02*
G03X386687Y526487I16J199D01*
G02X389019Y526802I2334J-8487D01*
G02Y509198I0J-8802D01*
G02X386687Y509513I2J8802D01*
G03X386620Y509519I-51J-193D01*
G02X386027Y509498I-597J8481D01*
G01X386019D01*
G02Y526502I0J8502D01*
G01X386027D01*
G02X386620Y526481I-4J-8502D01*
G37*
G36*
G01X434620D02*
G03X434687Y526487I16J199D01*
G02X437019Y526802I2334J-8487D01*
G02Y509198I0J-8802D01*
G02X434687Y509513I2J8802D01*
G03X434620Y509519I-51J-193D01*
G02X434027Y509498I-597J8481D01*
G01X434019D01*
G02Y526502I0J8502D01*
G01X434027D01*
G02X434620Y526481I-4J-8502D01*
G37*
G36*
G01X496101D02*
G03X496168Y526487I16J199D01*
G02X498500Y526802I2334J-8487D01*
G02Y509198I0J-8802D01*
G02X496168Y509513I2J8802D01*
G03X496101Y509519I-51J-193D01*
G02X495508Y509498I-597J8481D01*
G01X495500D01*
G02Y526502I0J8502D01*
G01X495508D01*
G02X496101Y526481I-4J-8502D01*
G37*
G36*
G01X544101D02*
G03X544168Y526487I16J199D01*
G02X546500Y526802I2334J-8487D01*
G02Y509198I0J-8802D01*
G02X544168Y509513I2J8802D01*
G03X544101Y509519I-51J-193D01*
G02X543508Y509498I-597J8481D01*
G01X543500D01*
G02Y526502I0J8502D01*
G01X543508D01*
G02X544101Y526481I-4J-8502D01*
G37*
G36*
G01X592101D02*
G03X592168Y526487I16J199D01*
G02X594500Y526802I2334J-8487D01*
G02Y509198I0J-8802D01*
G02X592168Y509513I2J8802D01*
G03X592101Y509519I-51J-193D01*
G02X591508Y509498I-597J8481D01*
G01X591500D01*
G02Y526502I0J8502D01*
G01X591508D01*
G02X592101Y526481I-4J-8502D01*
G37*
G36*
G01X653582D02*
G03X653649Y526487I16J199D01*
G02X655981Y526802I2334J-8487D01*
G02Y509198I0J-8802D01*
G02X653649Y509513I2J8802D01*
G03X653582Y509519I-51J-193D01*
G02X652989Y509498I-597J8481D01*
G01X652981D01*
G02Y526502I0J8502D01*
G01X652989D01*
G02X653582Y526481I-4J-8502D01*
G37*
G36*
G01X701582D02*
G03X701649Y526487I16J199D01*
G02X703981Y526802I2334J-8487D01*
G02Y509198I0J-8802D01*
G02X701649Y509513I2J8802D01*
G03X701582Y509519I-51J-193D01*
G02X700989Y509498I-597J8481D01*
G01X700981D01*
G02Y526502I0J8502D01*
G01X700989D01*
G02X701582Y526481I-4J-8502D01*
G37*
G36*
G01X749582D02*
G03X749649Y526487I16J199D01*
G02X751981Y526802I2334J-8487D01*
G02Y509198I0J-8802D01*
G02X749649Y509513I2J8802D01*
G03X749582Y509519I-51J-193D01*
G02X748989Y509498I-597J8481D01*
G01X748981D01*
G02Y526502I0J8502D01*
G01X748989D01*
G02X749582Y526481I-4J-8502D01*
G37*
G36*
G01X161938Y542102D02*
G02X162439Y542602I501J-1D01*
G01X168639D01*
G02X169140Y542100I-1J-502D01*
G01Y535898D01*
G02X168639Y535398I-501J1D01*
G01X162439D01*
G02X161938Y535900I1J502D01*
G01Y542102D01*
G37*
G36*
G01X209938D02*
G02X210439Y542602I501J-1D01*
G01X216639D01*
G02X217140Y542100I-1J-502D01*
G01Y535898D01*
G02X216639Y535398I-501J1D01*
G01X210439D01*
G02X209938Y535900I1J502D01*
G01Y542102D01*
G37*
G36*
G01X257938D02*
G02X258439Y542602I501J-1D01*
G01X264639D01*
G02X265140Y542100I-1J-502D01*
G01Y535898D01*
G02X264639Y535398I-501J1D01*
G01X258439D01*
G02X257938Y535900I1J502D01*
G01Y542102D01*
G37*
G36*
G01X319418D02*
G02X319919Y542602I501J-1D01*
G01X326119D01*
G02X326620Y542100I-1J-502D01*
G01Y535898D01*
G02X326119Y535398I-501J1D01*
G01X319919D01*
G02X319418Y535900I1J502D01*
G01Y542102D01*
G37*
G36*
G01X367418D02*
G02X367919Y542602I501J-1D01*
G01X374119D01*
G02X374620Y542100I-1J-502D01*
G01Y535898D01*
G02X374119Y535398I-501J1D01*
G01X367919D01*
G02X367418Y535900I1J502D01*
G01Y542102D01*
G37*
G36*
G01X415418D02*
G02X415919Y542602I501J-1D01*
G01X422119D01*
G02X422620Y542100I-1J-502D01*
G01Y535898D01*
G02X422119Y535398I-501J1D01*
G01X415919D01*
G02X415418Y535900I1J502D01*
G01Y542102D01*
G37*
G36*
G01X476898Y542100D02*
G02X477400Y542602I502J0D01*
G01X483600D01*
G02X484102Y542100I0J-502D01*
G01Y535900D01*
G02X483600Y535398I-502J0D01*
G01X477400D01*
G02X476898Y535900I0J502D01*
G01Y542100D01*
G37*
G36*
G01X524898D02*
G02X525400Y542602I502J0D01*
G01X531600D01*
G02X532102Y542100I0J-502D01*
G01Y535900D01*
G02X531600Y535398I-502J0D01*
G01X525400D01*
G02X524898Y535900I0J502D01*
G01Y542100D01*
G37*
G36*
G01X572898D02*
G02X573400Y542602I502J0D01*
G01X579600D01*
G02X580102Y542100I0J-502D01*
G01Y535900D01*
G02X579600Y535398I-502J0D01*
G01X573400D01*
G02X572898Y535900I0J502D01*
G01Y542100D01*
G37*
G36*
G01X634380Y542102D02*
G02X634881Y542602I501J-1D01*
G01X641081D01*
G02X641582Y542100I-1J-502D01*
G01Y535898D01*
G02X641081Y535398I-501J1D01*
G01X634881D01*
G02X634380Y535900I1J502D01*
G01Y542102D01*
G37*
G36*
G01X682380D02*
G02X682881Y542602I501J-1D01*
G01X689081D01*
G02X689582Y542100I-1J-502D01*
G01Y535898D01*
G02X689081Y535398I-501J1D01*
G01X682881D01*
G02X682380Y535900I1J502D01*
G01Y542102D01*
G37*
G36*
G01X730380D02*
G02X730881Y542602I501J-1D01*
G01X737081D01*
G02X737582Y542100I-1J-502D01*
G01Y535898D01*
G02X737081Y535398I-501J1D01*
G01X730881D01*
G02X730380Y535900I1J502D01*
G01Y542102D01*
G37*
G36*
G01X546998Y247000D02*
G02X557002I5002J0D01*
G02X556710Y245317I-5002J1D01*
G03Y245183I189J-67D01*
G02X556986Y243905I-4709J-1686D01*
G03X557120Y243732I199J16D01*
G02X560502Y239000I-1619J-4732D01*
G01Y238998D01*
G02X560290Y237558I-5002J1D01*
G03Y237442I191J-58D01*
G02X560502Y236002I-4790J-1441D01*
G01Y236000D01*
G02X550498I-5002J0D01*
G01Y236002D01*
G02X550710Y237442I5002J-1D01*
G03Y237558I-191J58D01*
G02X550514Y238595I4790J1442D01*
G03X550380Y238768I-199J-16D01*
G02X546998Y243500I1619J4732D01*
G02X547290Y245183I5002J-1D01*
G03Y245317I-189J67D01*
G02X546998Y247000I4710J1684D01*
G37*
G36*
G01X393198D02*
G02X403802I5302J0D01*
G02X403169Y244488I-5301J0D01*
G03X403159Y244320I176J-95D01*
G02X403450Y243221I-4659J-1822D01*
G03X403588Y243059I198J29D01*
G02X407302Y238000I-1589J-5059D01*
G02X406926Y236039I-5302J0D01*
G03X406915Y235928I186J-74D01*
G02X407002Y235000I-4915J-929D01*
G02X396998I-5002J0D01*
G02X397085Y235928I5002J-1D01*
G03X397074Y236039I-197J37D01*
G02X396706Y237706I4926J1962D01*
G03X396583Y237880I-200J-11D01*
G02X393498Y242500I1917J4620D01*
G02X393841Y244320I5002J0D01*
G03X393831Y244488I-186J73D01*
G02X393198Y247000I4668J2512D01*
G37*
G36*
G01X599645Y204298D02*
G02X599498Y205500I4855J1204D01*
G02X609502I5002J0D01*
G02X609355Y204298I-5002J2D01*
G03Y204202I195J-48D01*
G02X609502Y203000I-4855J-1204D01*
G02X608886Y200596I-5002J1D01*
G03Y200404I176J-96D01*
G02X609502Y198000I-4386J-2405D01*
G02X609355Y196798I-5002J2D01*
G03Y196702I195J-48D01*
G02X609502Y195500I-4855J-1204D01*
G02X599498I-5002J0D01*
G02X599645Y196702I5002J-2D01*
G03Y196798I-195J48D01*
G02X599498Y198000I4855J1204D01*
G02X600114Y200404I5002J-1D01*
G03Y200596I-176J96D01*
G02X599498Y203000I4386J2405D01*
G02X599645Y204202I5002J-2D01*
G03Y204298I-195J48D01*
G37*
G36*
G01X621145D02*
G02X620998Y205500I4855J1204D01*
G02X631002I5002J0D01*
G02X630855Y204298I-5002J2D01*
G03Y204202I195J-48D01*
G02X631002Y203000I-4855J-1204D01*
G02X630386Y200596I-5002J1D01*
G03Y200404I176J-96D01*
G02X631002Y198000I-4386J-2405D01*
G02X630855Y196798I-5002J2D01*
G03Y196702I195J-48D01*
G02X631002Y195500I-4855J-1204D01*
G02X620998I-5002J0D01*
G02X621145Y196702I5002J-2D01*
G03Y196798I-195J48D01*
G02X620998Y198000I4855J1204D01*
G02X621614Y200404I5002J-1D01*
G03Y200596I-176J96D01*
G02X620998Y203000I4386J2405D01*
G02X621145Y204202I5002J-2D01*
G03Y204298I-195J48D01*
G37*
G36*
G01X642645D02*
G02X642498Y205500I4855J1204D01*
G02X652502I5002J0D01*
G02X652355Y204298I-5002J2D01*
G03Y204202I195J-48D01*
G02X652502Y203000I-4855J-1204D01*
G02X651886Y200596I-5002J1D01*
G03Y200404I176J-96D01*
G02X652502Y198000I-4386J-2405D01*
G02X652355Y196798I-5002J2D01*
G03Y196702I195J-48D01*
G02X652502Y195500I-4855J-1204D01*
G02X642498I-5002J0D01*
G02X642645Y196702I5002J-2D01*
G03Y196798I-195J48D01*
G02X642498Y198000I4855J1204D01*
G02X643114Y200404I5002J-1D01*
G03Y200596I-176J96D01*
G02X642498Y203000I4386J2405D01*
G02X642645Y204202I5002J-2D01*
G03Y204298I-195J48D01*
G37*
G36*
G01X664145D02*
G02X663998Y205500I4855J1204D01*
G02X674002I5002J0D01*
G02X673855Y204298I-5002J2D01*
G03Y204202I195J-48D01*
G02X674002Y203000I-4855J-1204D01*
G02X673386Y200596I-5002J1D01*
G03Y200404I176J-96D01*
G02X674002Y198000I-4386J-2405D01*
G02X673855Y196798I-5002J2D01*
G03Y196702I195J-48D01*
G02X674002Y195500I-4855J-1204D01*
G02X663998I-5002J0D01*
G02X664145Y196702I5002J-2D01*
G03Y196798I-195J48D01*
G02X663998Y198000I4855J1204D01*
G02X664614Y200404I5002J-1D01*
G03Y200596I-176J96D01*
G02X663998Y203000I4386J2405D01*
G02X664145Y204202I5002J-2D01*
G03Y204298I-195J48D01*
G37*
G36*
G01X685645D02*
G02X685498Y205500I4855J1204D01*
G02X695502I5002J0D01*
G02X695355Y204298I-5002J2D01*
G03Y204202I195J-48D01*
G02X695502Y203000I-4855J-1204D01*
G02X694886Y200596I-5002J1D01*
G03Y200404I176J-96D01*
G02X695502Y198000I-4386J-2405D01*
G02X695355Y196798I-5002J2D01*
G03Y196702I195J-48D01*
G02X695502Y195500I-4855J-1204D01*
G02X685498I-5002J0D01*
G02X685645Y196702I5002J-2D01*
G03Y196798I-195J48D01*
G02X685498Y198000I4855J1204D01*
G02X686114Y200404I5002J-1D01*
G03Y200596I-176J96D01*
G02X685498Y203000I4386J2405D01*
G02X685645Y204202I5002J-2D01*
G03Y204298I-195J48D01*
G37*
G36*
G01X707135D02*
G02X706988Y205500I4855J1204D01*
G02X716992I5002J0D01*
G02X716845Y204298I-5002J2D01*
G03Y204202I195J-48D01*
G02X716992Y203000I-4855J-1204D01*
G02X716376Y200596I-5002J1D01*
G03Y200404I176J-96D01*
G02X716992Y198000I-4386J-2405D01*
G02X716845Y196798I-5002J2D01*
G03Y196702I195J-48D01*
G02X716992Y195500I-4855J-1204D01*
G02X706988I-5002J0D01*
G02X707135Y196702I5002J-2D01*
G03Y196798I-195J48D01*
G02X706988Y198000I4855J1204D01*
G02X707604Y200404I5002J-1D01*
G03Y200596I-176J96D01*
G02X706988Y203000I4386J2405D01*
G02X707135Y204202I5002J-2D01*
G03Y204298I-195J48D01*
G37*
G36*
G01X728635D02*
G02X728488Y205500I4855J1204D01*
G02X738492I5002J0D01*
G02X738345Y204298I-5002J2D01*
G03Y204202I195J-48D01*
G02X738492Y203000I-4855J-1204D01*
G02X737876Y200596I-5002J1D01*
G03Y200404I176J-96D01*
G02X738492Y198000I-4386J-2405D01*
G02X738345Y196798I-5002J2D01*
G03Y196702I195J-48D01*
G02X738492Y195500I-4855J-1204D01*
G02X728488I-5002J0D01*
G02X728635Y196702I5002J-2D01*
G03Y196798I-195J48D01*
G02X728488Y198000I4855J1204D01*
G02X729104Y200404I5002J-1D01*
G03Y200596I-176J96D01*
G02X728488Y203000I4386J2405D01*
G02X728635Y204202I5002J-2D01*
G03Y204298I-195J48D01*
G37*
G36*
G01X292145Y204798D02*
G02X291998Y206000I4855J1204D01*
G02X302002I5002J0D01*
G02X301855Y204798I-5002J2D01*
G03Y204702I195J-48D01*
G02X302002Y203500I-4855J-1204D01*
G02X301386Y201096I-5002J1D01*
G03Y200904I176J-96D01*
G02X302002Y198500I-4386J-2405D01*
G02X301855Y197298I-5002J2D01*
G03Y197202I195J-48D01*
G02X302002Y196000I-4855J-1204D01*
G02X291998I-5002J0D01*
G02X292145Y197202I5002J-2D01*
G03Y197298I-195J48D01*
G02X291998Y198500I4855J1204D01*
G02X292614Y200904I5002J-1D01*
G03Y201096I-176J96D01*
G02X291998Y203500I4386J2405D01*
G02X292145Y204702I5002J-2D01*
G03Y204798I-195J48D01*
G37*
G36*
G01X313645D02*
G02X313498Y206000I4855J1204D01*
G02X323502I5002J0D01*
G02X323355Y204798I-5002J2D01*
G03Y204702I195J-48D01*
G02X323502Y203500I-4855J-1204D01*
G02X322886Y201096I-5002J1D01*
G03Y200904I176J-96D01*
G02X323502Y198500I-4386J-2405D01*
G02X323355Y197298I-5002J2D01*
G03Y197202I195J-48D01*
G02X323502Y196000I-4855J-1204D01*
G02X313498I-5002J0D01*
G02X313645Y197202I5002J-2D01*
G03Y197298I-195J48D01*
G02X313498Y198500I4855J1204D01*
G02X314114Y200904I5002J-1D01*
G03Y201096I-176J96D01*
G02X313498Y203500I4386J2405D01*
G02X313645Y204702I5002J-2D01*
G03Y204798I-195J48D01*
G37*
G36*
G01X335145D02*
G02X334998Y206000I4855J1204D01*
G02X345002I5002J0D01*
G02X344855Y204798I-5002J2D01*
G03Y204702I195J-48D01*
G02X345002Y203500I-4855J-1204D01*
G02X344386Y201096I-5002J1D01*
G03Y200904I176J-96D01*
G02X345002Y198500I-4386J-2405D01*
G02X344855Y197298I-5002J2D01*
G03Y197202I195J-48D01*
G02X345002Y196000I-4855J-1204D01*
G02X334998I-5002J0D01*
G02X335145Y197202I5002J-2D01*
G03Y197298I-195J48D01*
G02X334998Y198500I4855J1204D01*
G02X335614Y200904I5002J-1D01*
G03Y201096I-176J96D01*
G02X334998Y203500I4386J2405D01*
G02X335145Y204702I5002J-2D01*
G03Y204798I-195J48D01*
G37*
G36*
G01X356645D02*
G02X356498Y206000I4855J1204D01*
G02X366502I5002J0D01*
G02X366355Y204798I-5002J2D01*
G03Y204702I195J-48D01*
G02X366502Y203500I-4855J-1204D01*
G02X365886Y201096I-5002J1D01*
G03Y200904I176J-96D01*
G02X366502Y198500I-4386J-2405D01*
G02X366355Y197298I-5002J2D01*
G03Y197202I195J-48D01*
G02X366502Y196000I-4855J-1204D01*
G02X356498I-5002J0D01*
G02X356645Y197202I5002J-2D01*
G03Y197298I-195J48D01*
G02X356498Y198500I4855J1204D01*
G02X357114Y200904I5002J-1D01*
G03Y201096I-176J96D01*
G02X356498Y203500I4386J2405D01*
G02X356645Y204702I5002J-2D01*
G03Y204798I-195J48D01*
G37*
G36*
G01X378145D02*
G02X377998Y206000I4855J1204D01*
G02X388002I5002J0D01*
G02X387855Y204798I-5002J2D01*
G03Y204702I195J-48D01*
G02X388002Y203500I-4855J-1204D01*
G02X387386Y201096I-5002J1D01*
G03Y200904I176J-96D01*
G02X388002Y198500I-4386J-2405D01*
G02X387855Y197298I-5002J2D01*
G03Y197202I195J-48D01*
G02X388002Y196000I-4855J-1204D01*
G02X377998I-5002J0D01*
G02X378145Y197202I5002J-2D01*
G03Y197298I-195J48D01*
G02X377998Y198500I4855J1204D01*
G02X378614Y200904I5002J-1D01*
G03Y201096I-176J96D01*
G02X377998Y203500I4386J2405D01*
G02X378145Y204702I5002J-2D01*
G03Y204798I-195J48D01*
G37*
G36*
G01X399645D02*
G02X399498Y206000I4855J1204D01*
G02X409502I5002J0D01*
G02X409355Y204798I-5002J2D01*
G03Y204702I195J-48D01*
G02X409502Y203500I-4855J-1204D01*
G02X408886Y201096I-5002J1D01*
G03Y200904I176J-96D01*
G02X409502Y198500I-4386J-2405D01*
G02X409355Y197298I-5002J2D01*
G03Y197202I195J-48D01*
G02X409502Y196000I-4855J-1204D01*
G02X399498I-5002J0D01*
G02X399645Y197202I5002J-2D01*
G03Y197298I-195J48D01*
G02X399498Y198500I4855J1204D01*
G02X400114Y200904I5002J-1D01*
G03Y201096I-176J96D01*
G02X399498Y203500I4386J2405D01*
G02X399645Y204702I5002J-2D01*
G03Y204798I-195J48D01*
G37*
G36*
G01X421145D02*
G02X420998Y206000I4855J1204D01*
G02X431002I5002J0D01*
G02X430855Y204798I-5002J2D01*
G03Y204702I195J-48D01*
G02X431002Y203500I-4855J-1204D01*
G02X430386Y201096I-5002J1D01*
G03Y200904I176J-96D01*
G02X431002Y198500I-4386J-2405D01*
G02X430855Y197298I-5002J2D01*
G03Y197202I195J-48D01*
G02X431002Y196000I-4855J-1204D01*
G02X420998I-5002J0D01*
G02X421145Y197202I5002J-2D01*
G03Y197298I-195J48D01*
G02X420998Y198500I4855J1204D01*
G02X421614Y200904I5002J-1D01*
G03Y201096I-176J96D01*
G02X420998Y203500I4386J2405D01*
G02X421145Y204702I5002J-2D01*
G03Y204798I-195J48D01*
G37*
G36*
G01X264498Y243000D02*
G02X265000Y243502I502J0D01*
G01X271000D01*
G02X271502Y243000I0J-502D01*
G01Y237000D01*
G02X271000Y236498I-502J0D01*
G01X265000D01*
G02X264498Y237000I0J502D01*
G01Y243000D01*
G37*
G36*
G01X308998D02*
G02X309500Y243502I502J0D01*
G01X315500D01*
G02X316002Y243000I0J-502D01*
G01Y237000D01*
G02X315500Y236498I-502J0D01*
G01X309500D01*
G02X308998Y237000I0J502D01*
G01Y243000D01*
G37*
G36*
G01X353498D02*
G02X354000Y243502I502J0D01*
G01X360000D01*
G02X360502Y243000I0J-502D01*
G01Y237000D01*
G02X360000Y236498I-502J0D01*
G01X354000D01*
G02X353498Y237000I0J502D01*
G01Y243000D01*
G37*
G36*
G01X424998D02*
G02X425500Y243502I502J0D01*
G01X431500D01*
G02X432002Y243000I0J-502D01*
G01Y237000D01*
G02X431500Y236498I-502J0D01*
G01X425500D01*
G02X424998Y237000I0J502D01*
G01Y243000D01*
G37*
G36*
G01X468998D02*
G02X469500Y243502I502J0D01*
G01X475500D01*
G02X476002Y243000I0J-502D01*
G01Y237000D01*
G02X475500Y236498I-502J0D01*
G01X469500D01*
G02X468998Y237000I0J502D01*
G01Y243000D01*
G37*
G36*
G01X512998D02*
G02X513500Y243502I502J0D01*
G01X519500D01*
G02X520002Y243000I0J-502D01*
G01Y237000D01*
G02X519500Y236498I-502J0D01*
G01X513500D01*
G02X512998Y237000I0J502D01*
G01Y243000D01*
G37*
G36*
G01X574998D02*
G02X575500Y243502I502J0D01*
G01X581500D01*
G02X582002Y243000I0J-502D01*
G01Y237000D01*
G02X581500Y236498I-502J0D01*
G01X575500D01*
G02X574998Y237000I0J502D01*
G01Y243000D01*
G37*
G36*
G01X618998D02*
G02X619500Y243502I502J0D01*
G01X625500D01*
G02X626002Y243000I0J-502D01*
G01Y237000D01*
G02X625500Y236498I-502J0D01*
G01X619500D01*
G02X618998Y237000I0J502D01*
G01Y243000D01*
G37*
G36*
G01X662998D02*
G02X663500Y243502I502J0D01*
G01X669500D01*
G02X670002Y243000I0J-502D01*
G01Y237000D01*
G02X669500Y236498I-502J0D01*
G01X663500D01*
G02X662998Y237000I0J502D01*
G01Y243000D01*
G37*
G36*
G01X732480Y243002D02*
G02X732981Y243502I501J-1D01*
G01X738981D01*
G02X739482Y243000I-1J-502D01*
G01Y236998D01*
G02X738981Y236498I-501J1D01*
G01X732981D01*
G02X732480Y237000I1J502D01*
G01Y243002D01*
G37*
G36*
G01X776480D02*
G02X776981Y243502I501J-1D01*
G01X782981D01*
G02X783482Y243000I-1J-502D01*
G01Y236998D01*
G02X782981Y236498I-501J1D01*
G01X776981D01*
G02X776480Y237000I1J502D01*
G01Y243002D01*
G37*
G36*
G01X820480D02*
G02X820981Y243502I501J-1D01*
G01X826981D01*
G02X827482Y243000I-1J-502D01*
G01Y236998D01*
G02X826981Y236498I-501J1D01*
G01X820981D01*
G02X820480Y237000I1J502D01*
G01Y243002D01*
G37*
G36*
G01X1061600Y271242D02*
G02X1066600Y276242I0J5000D01*
G02X1066510Y275298I-5000J0D01*
G02X1067701Y275442I1191J-4856D01*
G02X1062701Y270442I0J-5000D01*
G02X1062791Y271386I5000J0D01*
G02X1061600Y271242I-1191J4856D01*
G37*
G36*
G01Y318742D02*
G02X1066600Y323742I0J5000D01*
G02X1066511Y322804I-5000J1D01*
G02X1067676Y322942I1167J-4862D01*
G01X1067679D01*
G02X1062679Y317942I0J-5000D01*
G02X1062768Y318880I5000J-1D01*
G02X1061603Y318742I-1167J4862D01*
G01X1061600D01*
G37*
G36*
G01Y461242D02*
G02X1066600Y466242I0J5000D01*
G02X1066489Y465196I-5000J2D01*
G02X1067726Y465352I1239J-4844D01*
G01X1067730D01*
G02X1062730Y460352I0J-5000D01*
G02X1062841Y461398I5000J-2D01*
G02X1061604Y461242I-1239J4844D01*
G01X1061600D01*
G37*
G36*
G01Y508742D02*
G02X1066600Y513742I0J5000D01*
G02X1066421Y512416I-5001J0D01*
G02X1067864Y512629I1444J-4787D01*
G01X1067866D01*
G02X1062866Y507629I0J-5000D01*
G02X1063045Y508955I5001J0D01*
G02X1061602Y508742I-1444J4787D01*
G01X1061600D01*
G37*
G54D84*
X183900Y216830D03*
G54D79*
X154840Y244730D03*
G54D80*
X166068Y238749D03*
X160017Y237764D03*
X175976Y218775D03*
X1043936Y145745D03*
G54D90*
X268000Y220315D03*
X312500D03*
X357000D03*
X428500D03*
X472500D03*
X516500D03*
X578500D03*
X622500D03*
X666500D03*
X735981D03*
X779981D03*
X823981D03*
G54D87*
X185224Y539000D03*
X233224D03*
X281224D03*
X342704D03*
X390704D03*
X438704D03*
X500185D03*
X548185D03*
X596185D03*
X657666D03*
X705666D03*
X753666D03*
G54D88*
X268819Y277204D03*
G54D86*
X193819Y477204D03*
X351299D03*
X508780D03*
X666261D03*
G54D92*
X1226024Y399429D03*
G54D91*
Y174429D03*
G54D89*
X529252Y129685D03*
X665059Y149408D03*
G54D81*
X211000Y26000D03*
G54D82*
X175000Y100500D03*
G54D85*
X19922Y214173D03*
G54D83*
X249252Y129685D03*
%LPD*%
G75*
G36*
G01X143500Y219502D02*
Y233350D01*
G02X143559Y233492I200J0D01*
G01X143607Y233540D01*
G02X143748Y233598I141J-142D01*
G01X144191D01*
X144204Y233597D01*
G03X144730Y233562I528J3966D01*
G01X149738D01*
G03X150264Y233597I-2J4001D01*
G01X150277Y233598D01*
X153360D01*
G02X153502Y233539I0J-200D01*
G01X155550Y231491D01*
G03X155692Y231432I142J141D01*
G01X156800D01*
G02X157000Y231232I0J-200D01*
G01Y219502D01*
G02X156800Y219302I-200J0D01*
G01X152279D01*
G02X152085Y219450I-1J200D01*
G03X149183I-1451J-387D01*
G02X148989Y219302I-193J52D01*
G01X143700D01*
G02X143500Y219502I0J200D01*
G37*
G54D10*
G01X208071Y303575D02*
Y305975D01*
G01X216075Y305000D02*
X218500D01*
G01X224575D02*
X226975D01*
G01X233575D02*
X235975D01*
G01X239567Y303575D02*
Y305975D01*
G01X223819Y447425D02*
Y445025D01*
G01X247441Y303575D02*
Y305975D01*
G01X373075Y305000D02*
X375475D01*
G01X381575D02*
X383975D01*
G01X390575D02*
X393000D01*
G01X365551Y303575D02*
Y305975D01*
G01X381299Y447425D02*
Y445025D01*
G01X397047Y303575D02*
Y305975D01*
G01X426456Y444260D02*
X430019D01*
G01X432019Y454425D02*
Y452025D01*
G01X531075Y305500D02*
X533475D01*
G01X523032Y303575D02*
Y305975D01*
G01X538780Y447425D02*
Y445025D01*
G01X540075Y305500D02*
X542475D01*
G01X549075D02*
X551475D01*
G01X554528Y303575D02*
Y305975D01*
G01X562402Y303575D02*
Y305975D01*
G01X583937Y444260D02*
X587500D01*
G01X680513Y303575D02*
Y305975D01*
G01X688556Y305500D02*
X690956D01*
G01X706556D02*
X708956D01*
G01X712009Y303575D02*
Y305975D01*
G01X697556Y305500D02*
X700000D01*
G01X696261Y447425D02*
Y445024D01*
G01X719883Y303575D02*
Y305975D01*
G01X742500Y361500D02*
X744925D01*
G01X808500Y272925D02*
X811000D01*
G01X831000Y260500D02*
Y262925D01*
G01X826000Y260525D02*
Y262925D01*
G01X819500Y329000D02*
Y326575D01*
G01X827500Y329000D02*
Y326575D01*
G01X825941Y339560D02*
Y342260D01*
G01X813975Y362000D02*
X811575D01*
G01X813975Y357000D02*
X811575D01*
G01X835610Y355590D02*
Y356075D01*
X833610Y358075D01*
X832500D01*
G01X836000Y260500D02*
Y262925D01*
G01X841000Y260525D02*
Y262925D01*
G01X846000Y260525D02*
Y262925D01*
G01X851000Y260525D02*
Y262925D01*
G01X856000Y260525D02*
Y262925D01*
G01X837575Y321000D02*
Y323500D01*
G01X865000Y313200D02*
Y318100D01*
G01X844760Y336077D02*
Y340177D01*
G01X850500Y360075D02*
X853000D01*
G01X894500Y283475D02*
Y281075D01*
G01X884000Y283475D02*
Y281075D01*
G01X877500Y283475D02*
Y281075D01*
G01X893363Y298740D02*
X890063D01*
G01X883000Y293925D02*
X880000D01*
G01D02*
X875000D01*
G01D02*
X870000D01*
G01X878000Y358475D02*
Y356075D01*
G01X883000Y358500D02*
Y356075D01*
G01X915500Y283475D02*
Y281075D01*
G01X914500Y292000D02*
Y294425D01*
G01X905000Y283475D02*
Y281075D01*
G01X905941Y306500D02*
Y309260D01*
G01X912500Y327975D02*
Y325575D01*
G01X916260Y337077D02*
Y341177D01*
G01X908000Y327975D02*
Y325575D01*
G01X901063Y352340D02*
Y349240D01*
G01X933000Y293476D02*
Y291075D01*
G01X940000Y293476D02*
Y291075D01*
G01X947000Y293476D02*
Y291075D01*
G01X933196Y309910D02*
Y312310D01*
G01X927000Y361075D02*
X924500D01*
G01X1077268Y359443D02*
X1077069Y359642D01*
G01X1080418Y363443D02*
Y373600D01*
X3005Y19808D03*
Y34808D03*
Y59808D03*
X7595Y128373D03*
X3005Y145238D03*
Y165238D03*
Y185238D03*
Y205238D03*
Y225238D03*
Y245238D03*
Y265238D03*
Y285238D03*
Y305238D03*
Y325238D03*
Y345238D03*
Y365238D03*
Y385238D03*
Y405238D03*
Y425238D03*
Y445238D03*
X3023Y524312D03*
Y549312D03*
X4540Y566003D03*
X34582Y3004D03*
X14811Y3732D03*
X12767Y72072D03*
X27271Y127298D03*
X19558Y454589D03*
X9913Y510026D03*
X20498Y575739D03*
X54582Y3004D03*
X63436Y353962D03*
X39549Y454916D03*
X40498Y575739D03*
X60498D03*
X94582Y3004D03*
X74582D03*
X80498Y575739D03*
X114582Y3004D03*
X108600Y258560D03*
X111600D03*
X108600Y261560D03*
X111600D03*
X108600Y255560D03*
X111600D03*
X123000Y414500D03*
X119500D03*
Y411500D03*
X123000D03*
X119500Y408500D03*
X123000D03*
X119500Y417500D03*
X123000D03*
X119500Y420500D03*
X123000D03*
X115700Y420600D03*
Y417600D03*
Y408600D03*
Y411600D03*
Y414600D03*
X123000Y426600D03*
X119500D03*
X123000Y423600D03*
X119500D03*
X115700Y423700D03*
Y426700D03*
X100498Y575739D03*
X120498D03*
X154582Y3004D03*
X134582D03*
X153480Y213350D03*
X150634Y219063D03*
X155140Y240230D03*
X155034Y228063D03*
Y224563D03*
X152334Y223063D03*
Y226563D03*
Y230063D03*
X155034Y231563D03*
X140400Y258360D03*
X143400D03*
X140400Y261360D03*
X143400D03*
X140400Y255360D03*
X143400D03*
X140498Y575739D03*
X174582Y3004D03*
X172934Y219110D03*
X184349Y212651D03*
X182260Y197050D03*
X179460D03*
X176560D03*
X174660Y205850D03*
Y202650D03*
X167660Y213050D03*
X164760D03*
X167660Y209850D03*
X164760D03*
X183900Y216830D03*
X172712Y222263D03*
X183815Y220903D03*
X165840Y247805D03*
X169840D03*
X175481Y225183D03*
X161400Y323200D03*
X173265Y340552D03*
X157000Y414500D03*
X160500D03*
Y417500D03*
X157000D03*
X160500Y420500D03*
X157000D03*
X160500Y411500D03*
X157000D03*
X160500Y408500D03*
X157000D03*
X164000Y414600D03*
Y417600D03*
Y420600D03*
Y411600D03*
Y408600D03*
X160300Y423600D03*
X156800D03*
X160300Y426600D03*
X156800D03*
X163800Y426700D03*
Y423700D03*
X180539Y498000D03*
X168939D03*
X180539Y518000D03*
X168939D03*
X214582Y3004D03*
X194582D03*
X194160Y205200D03*
Y208200D03*
X200160Y205200D03*
Y208200D03*
X197160Y205200D03*
Y208200D03*
X185260Y205350D03*
Y208350D03*
X189760Y242100D03*
Y245100D03*
X192760Y242100D03*
Y245100D03*
X195760Y242100D03*
Y245100D03*
X198760Y242100D03*
Y245100D03*
X201760Y242100D03*
Y245100D03*
X208071Y305975D03*
X203575Y297500D03*
X212925Y315500D03*
X234582Y3004D03*
X242500Y243000D03*
Y247500D03*
X218500Y305000D03*
X226975D03*
X235975D03*
X239567Y305975D03*
X218500Y309500D03*
X226975D03*
X235975D03*
X230425Y313605D03*
X221425Y313000D03*
X223819Y445025D03*
X228539Y498000D03*
X216939D03*
X228539Y518000D03*
X216939D03*
X254582Y3004D03*
X246000Y235500D03*
X247441Y305975D03*
X264939Y498000D03*
Y518000D03*
X294582Y3004D03*
X274582D03*
X297000Y206000D03*
Y203500D03*
Y198500D03*
Y196000D03*
X283000Y203500D03*
Y198500D03*
Y196000D03*
Y206000D03*
X285219Y279078D03*
X281219D03*
X277219D03*
X285219Y275078D03*
X281219D03*
X277219D03*
X285219Y271078D03*
X281219D03*
X277219D03*
Y283078D03*
X281219D03*
X285219D03*
X290720Y340338D03*
X276539Y498000D03*
Y518000D03*
X314582Y3004D03*
X318500Y206000D03*
Y203500D03*
Y198500D03*
Y196000D03*
X326000Y203500D03*
Y198500D03*
Y196000D03*
Y206000D03*
X304500Y203500D03*
Y198500D03*
Y196000D03*
Y206000D03*
X313571Y340552D03*
X326419Y498000D03*
Y518000D03*
X354582Y3004D03*
X334582D03*
X340000Y206000D03*
Y203500D03*
Y198500D03*
Y196000D03*
X361500Y206000D03*
Y203500D03*
Y198500D03*
Y196000D03*
X347500Y203500D03*
Y198500D03*
Y196000D03*
Y206000D03*
X361000Y305975D03*
X338019Y498000D03*
Y518000D03*
X374582Y3004D03*
X383000Y206000D03*
Y203500D03*
Y198500D03*
Y196000D03*
X390500Y203500D03*
Y198500D03*
Y196000D03*
Y206000D03*
X369000Y203500D03*
Y198500D03*
Y196000D03*
Y206000D03*
X375475Y305000D03*
X383975D03*
X365551Y305975D03*
X375500Y309500D03*
X383975D03*
X382963Y316400D03*
Y313750D03*
X381299Y445025D03*
X386019Y498000D03*
X374419D03*
X386019Y518000D03*
X374419D03*
X414582Y3004D03*
X394582D03*
X404500Y206000D03*
Y203500D03*
Y198500D03*
Y196000D03*
X412000Y203500D03*
Y198500D03*
Y196000D03*
Y206000D03*
X402000Y235000D03*
X398500Y242500D03*
X393000Y305000D03*
X397047Y305975D03*
X404921D03*
X392975Y309500D03*
X434582Y3004D03*
X426000Y206000D03*
Y203500D03*
Y198500D03*
Y196000D03*
X442499Y279186D03*
X438499D03*
X434499D03*
X442499Y275186D03*
X438499D03*
X434499D03*
X442499Y271186D03*
X438499D03*
X434499D03*
Y283186D03*
X438499D03*
X442499D03*
X447255Y340339D03*
X430019Y444260D03*
X432019Y452025D03*
X434019Y498000D03*
X422419D03*
X434019Y518000D03*
X422419D03*
X474582Y3004D03*
X454582D03*
X473095Y340339D03*
X494582Y3004D03*
X495500Y498000D03*
X483900D03*
X495500Y518000D03*
X483900D03*
X534582Y3004D03*
X514582D03*
X533475Y305500D03*
X523032Y305975D03*
X518575Y295500D03*
X533475Y310500D03*
X539619Y316400D03*
Y313400D03*
X538780Y445025D03*
X531900Y498000D03*
Y518000D03*
X554582Y3004D03*
X555500Y239000D03*
Y236000D03*
X552000Y243500D03*
Y247000D03*
X542475Y305500D03*
X551475D03*
X554528Y305975D03*
X562402D03*
X542475Y310500D03*
X551475D03*
X545063Y340339D03*
X549500Y445024D03*
X562000Y442000D03*
X564500D03*
X543500Y498000D03*
Y518000D03*
X594582Y3004D03*
X574582D03*
X590500Y203000D03*
Y198000D03*
Y195500D03*
Y205500D03*
X587500Y444260D03*
X589500Y446500D03*
X591500Y498000D03*
X579900D03*
X591500Y518000D03*
X579900D03*
X614582Y3004D03*
X604500Y205500D03*
Y203000D03*
Y198000D03*
Y195500D03*
X626000Y205500D03*
Y203000D03*
Y198000D03*
Y195500D03*
X612000Y203000D03*
Y198000D03*
Y195500D03*
Y205500D03*
X654582Y3004D03*
X634582D03*
X640900Y42300D03*
X647999Y33000D03*
X655300Y56800D03*
X638200Y44000D03*
Y46500D03*
X641100Y48100D03*
X647500Y205500D03*
Y203000D03*
Y198000D03*
Y195500D03*
X655000Y203000D03*
Y198000D03*
Y195500D03*
Y205500D03*
X633500Y203000D03*
Y198000D03*
Y195500D03*
Y205500D03*
X652981Y498000D03*
X641381D03*
X652981Y518000D03*
X641381D03*
X674582Y3004D03*
X684525Y36500D03*
X679000Y56800D03*
X686500D03*
X671100D03*
X663200D03*
X669000Y205500D03*
Y203000D03*
Y198000D03*
Y195500D03*
X676500D03*
Y198000D03*
Y203000D03*
Y205500D03*
X680513Y305975D03*
X676075Y299600D03*
X714582Y3004D03*
X694582D03*
X699500Y34500D03*
X696900Y53300D03*
X694200D03*
X691400D03*
X689900Y56600D03*
X696100Y56700D03*
X690500Y205500D03*
Y203000D03*
Y198000D03*
Y195500D03*
X711990D03*
Y198000D03*
Y203000D03*
Y205500D03*
X697990Y195500D03*
Y198000D03*
Y203000D03*
Y205500D03*
X709500Y247000D03*
X709481Y243500D03*
X712981Y236000D03*
Y239000D03*
X716100Y255987D03*
X700040Y258960D03*
X712009Y305975D03*
X708956Y305500D03*
X690956D03*
X700000D03*
X694406Y295500D03*
X690956Y310500D03*
X699956D03*
X708956D03*
X697100Y313400D03*
X704400Y358600D03*
X702200Y356000D03*
X697900Y352500D03*
X707750Y358750D03*
X696261Y445024D03*
X700981Y498000D03*
X689381D03*
X700981Y518000D03*
X689381D03*
X734582Y3004D03*
X747160Y30000D03*
Y38500D03*
Y64000D03*
Y47000D03*
Y55500D03*
X733490Y195500D03*
Y198000D03*
Y203000D03*
Y205500D03*
X719490Y195500D03*
Y198000D03*
Y203000D03*
Y205500D03*
X719883Y305975D03*
X724000Y294500D03*
X732100Y332400D03*
X742500Y328500D03*
Y324500D03*
Y334500D03*
X735075Y326000D03*
Y336000D03*
X731925D03*
X732000Y326000D03*
X742500Y361500D03*
X742000Y341500D03*
X742500Y347700D03*
Y353200D03*
X737381Y498000D03*
Y518000D03*
X774582Y3004D03*
X754582D03*
X758760Y38500D03*
X756160D03*
X758760Y30000D03*
X756160D03*
X758900Y27400D03*
X750300Y27200D03*
X752560Y30100D03*
X749760D03*
X752560Y38600D03*
X749760D03*
X758760Y55500D03*
X756160D03*
X758760Y47000D03*
X756160D03*
X758760Y64000D03*
X756160D03*
X752560Y64100D03*
X749760D03*
X752560Y47100D03*
X749760D03*
X752560Y55600D03*
X749760D03*
X754000Y353500D03*
X748075Y366500D03*
X748981Y498000D03*
Y518000D03*
X794582Y3004D03*
X797854Y259539D03*
X803900Y279425D03*
X803500Y259525D03*
X806500Y285500D03*
X786500Y336484D03*
X800575Y338000D03*
X779100Y326820D03*
X798400Y323900D03*
X786500Y316700D03*
X793800Y323880D03*
X781500Y362700D03*
X803000Y357000D03*
Y346500D03*
X802975Y362000D03*
X792000Y358000D03*
X805323Y408150D03*
Y405150D03*
X799323D03*
Y408150D03*
X802323Y405150D03*
Y408150D03*
X796600Y408097D03*
Y405097D03*
X802323Y416916D03*
X799323D03*
X805323D03*
X802323Y413916D03*
X799323D03*
X805323D03*
Y411150D03*
X799323D03*
X802323D03*
X796600Y411097D03*
Y413863D03*
Y416863D03*
X799655Y474684D03*
Y480503D03*
Y477684D03*
X802655Y474684D03*
Y480503D03*
Y477684D03*
X805655Y474684D03*
Y480503D03*
Y477684D03*
X802655Y483503D03*
X805709Y486332D03*
X805655Y483503D03*
X796655Y474684D03*
Y480503D03*
Y477684D03*
X796709Y486332D03*
X796655Y483503D03*
X799709Y486332D03*
X799655Y483503D03*
X802709Y486332D03*
X834582Y3004D03*
X814582D03*
X809500Y259430D03*
X808500Y272925D03*
X831000Y260500D03*
X836000D03*
X826000Y260525D03*
X831000Y270500D03*
X808500Y276075D03*
X836000Y270500D03*
X826000Y270525D03*
X833500Y268575D03*
X821000Y270525D03*
X816000D03*
X827602Y283500D03*
X836500Y302500D03*
X814500Y293000D03*
X819500Y329000D03*
X827500D03*
X811500D03*
X815500D03*
X823500D03*
X819500Y318500D03*
X808425Y334000D03*
X831750Y318250D03*
X825941Y339560D03*
X813975Y362000D03*
Y357000D03*
X835610Y355590D03*
X829500Y354925D03*
X827000Y360475D03*
X811575Y344000D03*
X827000Y352500D03*
X808425Y344000D03*
X811323Y405150D03*
Y408150D03*
X808323D03*
Y405150D03*
Y416916D03*
X811323D03*
X808323Y413916D03*
X811323D03*
Y411150D03*
X808323D03*
X817153Y408096D03*
Y405096D03*
X814323Y405150D03*
Y408150D03*
Y416916D03*
X817153Y416862D03*
X814323Y413916D03*
X817153Y413862D03*
Y411096D03*
X814323Y411150D03*
X817709Y486332D03*
X817655Y483503D03*
X808655Y474684D03*
Y480503D03*
Y477684D03*
X811655Y474684D03*
Y480503D03*
Y477684D03*
X814655D03*
Y480503D03*
Y474684D03*
X808709Y486332D03*
X808655Y483503D03*
X811709Y486332D03*
X811655Y483503D03*
X814655D03*
X814709Y486332D03*
X817655Y474684D03*
Y480503D03*
Y477684D03*
X854582Y3004D03*
X849490Y196000D03*
Y198500D03*
Y203500D03*
Y206000D03*
X863600Y208900D03*
X841000Y260525D03*
X846000D03*
X851000D03*
X856000D03*
X841000Y270500D03*
X846000Y270525D03*
X851000D03*
X856000D03*
X843500Y268575D03*
X853500D03*
X850750Y250750D03*
X848075Y306500D03*
X861600Y304600D03*
X845000Y303000D03*
X837575Y321000D03*
X865000Y313200D03*
X844760Y336077D03*
X848500Y335800D03*
X839692Y329592D03*
X854825Y330925D03*
X850500Y360075D03*
Y366000D03*
X847500D03*
X856500D03*
X859500D03*
X865500D03*
X850500Y356925D03*
X843843Y354342D03*
X864500Y358500D03*
X849000Y399000D03*
X850390Y385878D03*
X847390D03*
X859253D03*
X856253D03*
X865542Y385771D03*
X859342Y413916D03*
X856342D03*
X865342D03*
X862342D03*
Y411150D03*
X865342D03*
X856342D03*
X859342D03*
X853619Y411097D03*
Y413863D03*
Y416863D03*
X862342Y408150D03*
Y405150D03*
X865342Y408150D03*
Y405150D03*
X856342D03*
Y408150D03*
X859342Y405150D03*
Y408150D03*
X853619Y408097D03*
Y405097D03*
X859342Y416916D03*
X856342D03*
X865342D03*
X862342D03*
X856257Y474684D03*
Y480503D03*
Y477684D03*
X859257Y474684D03*
Y480503D03*
Y477684D03*
X862257Y474684D03*
Y480503D03*
Y477684D03*
X859257Y483503D03*
X862311Y486332D03*
X862257Y483503D03*
X853257Y474684D03*
Y480503D03*
Y477684D03*
X853311Y486332D03*
X853257Y483503D03*
X856311Y486332D03*
X856257Y483503D03*
X859311Y486332D03*
X865311D03*
X865257Y483503D03*
Y474684D03*
Y480503D03*
Y477684D03*
X854082Y505410D03*
X848263D03*
X851082D03*
X854082Y508410D03*
X848263D03*
X851082D03*
X854082Y511410D03*
X848263D03*
X851082D03*
X854082Y514410D03*
X848263D03*
X851082D03*
X845263Y508410D03*
X842434Y511464D03*
X845263Y511410D03*
X842434Y514464D03*
X845263Y514410D03*
X854082Y502410D03*
X848263D03*
X851082D03*
X842434Y502464D03*
X845263Y502410D03*
X842434Y505464D03*
X845263Y505410D03*
X842434Y508464D03*
Y523464D03*
X845263Y523410D03*
X854082Y517410D03*
X848263D03*
X851082D03*
Y520410D03*
X848263D03*
X854082D03*
X842434Y517464D03*
X845263Y517410D03*
Y520410D03*
X842434Y520464D03*
X854082Y523410D03*
X848263D03*
X851082D03*
X894582Y3004D03*
X874582D03*
X868000Y271500D03*
X894500Y283475D03*
X884000D03*
X877500D03*
X893363Y298740D03*
X883000Y293925D03*
X867000Y291260D03*
X870000Y304525D03*
X875000D03*
X880000D03*
X888000Y283475D03*
X870000Y312788D03*
X880000Y312855D03*
X875000Y347273D03*
X877500Y366000D03*
X874500D03*
X884000D03*
X887000D03*
X893500D03*
X868500D03*
X878000Y358475D03*
X883000Y358500D03*
X874000Y358475D03*
X885500Y352925D03*
X893091Y385771D03*
X874405D03*
X877405D03*
X868542D03*
X884228D03*
X887228D03*
X868342Y416916D03*
X871342D03*
X868342Y413916D03*
X871342D03*
Y411150D03*
X868342D03*
X874172Y408096D03*
Y405096D03*
Y416862D03*
Y413862D03*
Y411096D03*
X871342Y405150D03*
Y408150D03*
X868342Y405150D03*
Y408150D03*
X868311Y486332D03*
X868257Y483503D03*
Y477684D03*
Y480503D03*
Y474684D03*
X871311Y486332D03*
X874311D03*
X874257Y477684D03*
Y480503D03*
Y474684D03*
X871257Y483503D03*
Y474684D03*
Y480503D03*
Y477684D03*
X874257Y483503D03*
X914582Y3004D03*
X915500Y283475D03*
X914500Y292000D03*
X905000Y283475D03*
X905941Y306500D03*
X909000Y283475D03*
X904500Y292000D03*
X912500Y327975D03*
X916260Y337077D03*
X908000Y327975D03*
X915000Y322425D03*
X912000Y332425D03*
X905941Y320366D03*
X903500Y327975D03*
X896500Y366000D03*
X906000D03*
X903000D03*
X912500D03*
X915500D03*
X922000D03*
X901063Y352340D03*
X916260Y355000D03*
X920000Y355525D03*
X923740Y345500D03*
X896091Y385771D03*
X912525Y385877D03*
X906662D03*
X903662D03*
X922454Y385771D03*
X915525Y385877D03*
X911776Y507184D03*
Y510184D03*
Y501184D03*
Y504184D03*
X923595Y498461D03*
X920595D03*
X920542Y504184D03*
X923542D03*
X920542Y501184D03*
X923542D03*
Y510184D03*
X920542D03*
X923542Y507184D03*
X920542D03*
Y513184D03*
X923542D03*
X911829Y498461D03*
X914829D03*
X917595D03*
X917542Y504184D03*
Y501184D03*
Y510184D03*
Y507184D03*
Y513184D03*
X914776D03*
Y507184D03*
Y510184D03*
Y501184D03*
Y504184D03*
X911776Y513184D03*
X920542Y516184D03*
X923542D03*
X917542D03*
X914776D03*
X911776D03*
X917596Y519014D03*
X914830D03*
X911830D03*
X923596D03*
X920596D03*
X934582Y3004D03*
X940575Y304000D03*
X933000Y293476D03*
X940000D03*
X947000D03*
X926000Y283475D03*
X937516Y300075D03*
X947000Y302475D03*
X940000Y283800D03*
X933196Y309910D03*
X930500Y315460D03*
X943172Y310885D03*
X943171Y315385D03*
X935516Y361075D03*
X925000Y366000D03*
X944000D03*
X941000D03*
X934500D03*
X950500D03*
X953500D03*
X931500D03*
X927000Y361075D03*
X941035Y344474D03*
X927000Y357925D03*
X943885Y352385D03*
X933357Y344843D03*
X933196Y353360D03*
X925454Y385771D03*
X944247Y385877D03*
X941247D03*
X931317Y385771D03*
X934317D03*
X950110Y385877D03*
X953110D03*
X940498Y575739D03*
X974582Y3004D03*
X954582D03*
X960498Y575739D03*
X980498D03*
X994582Y3004D03*
X1000498Y575739D03*
X1034582Y3004D03*
X1014582D03*
X1022575Y100925D03*
Y115500D03*
X1034500Y142000D03*
X1037000Y146300D03*
X1037500Y142000D03*
X1036500Y153500D03*
X1019030Y160330D03*
X1022168Y155877D03*
X1017837Y154280D03*
X1024340Y146600D03*
X1016614Y187267D03*
X1036500Y172000D03*
Y163000D03*
X1039538Y179208D03*
X1039016Y185925D03*
X1016614Y197767D03*
X1020498Y575739D03*
X1040498D03*
X1054582Y3004D03*
X1070400Y123200D03*
X1067600D03*
X1068900Y110000D03*
X1057525Y130500D03*
X1065000Y156425D03*
X1047159Y141487D03*
X1048000Y153500D03*
X1057525Y134000D03*
Y138600D03*
X1070715Y146500D03*
X1063500Y159814D03*
X1070715Y178585D03*
X1048000Y172000D03*
Y163000D03*
X1060500Y164500D03*
X1067000Y191500D03*
X1070000D03*
X1058000D03*
X1053830Y191670D03*
X1060000Y249000D03*
X1063000D03*
X1066000D03*
Y246000D03*
X1063000D03*
X1060000D03*
X1066000Y243000D03*
X1063000D03*
X1060000D03*
X1069000Y246000D03*
Y243000D03*
X1072000Y246000D03*
Y243000D03*
X1060000Y252000D03*
X1063000D03*
X1066000D03*
Y258000D03*
X1063000D03*
X1060000D03*
X1066000Y255000D03*
X1063000D03*
X1060000D03*
X1069000Y258000D03*
Y255000D03*
X1072000Y258000D03*
Y255000D03*
X1060000Y296500D03*
X1063000D03*
X1066000D03*
Y293500D03*
X1063000D03*
X1060000D03*
X1069000D03*
X1060000Y299500D03*
X1063000D03*
X1066000D03*
Y305500D03*
X1063000D03*
X1060000D03*
X1066000Y302500D03*
X1063000D03*
X1060000D03*
X1069000Y305500D03*
Y302500D03*
X1066000Y290500D03*
X1063000D03*
X1060000D03*
X1069000D03*
X1072000Y293500D03*
Y305500D03*
Y302500D03*
Y290500D03*
X1066000Y338000D03*
X1063000D03*
X1060000D03*
X1069000D03*
X1072000D03*
X1060000Y344000D03*
X1063000D03*
X1066000D03*
X1060000Y347000D03*
X1063000D03*
X1066000D03*
Y341000D03*
X1063000D03*
X1060000D03*
X1066000Y353000D03*
X1063000D03*
X1060000D03*
X1066000Y350000D03*
X1063000D03*
X1060000D03*
X1069000Y353000D03*
Y350000D03*
Y341000D03*
X1072000Y353000D03*
Y350000D03*
Y341000D03*
X1061600Y359642D03*
X1066000Y397500D03*
X1063000D03*
X1060000D03*
X1069000D03*
X1060000Y391500D03*
X1063000D03*
X1066000D03*
X1060000Y394500D03*
X1063000D03*
X1066000D03*
Y388500D03*
X1063000D03*
X1060000D03*
X1066000Y385500D03*
X1063000D03*
X1060000D03*
X1069000Y388500D03*
Y385500D03*
X1072000Y397500D03*
Y388500D03*
Y385500D03*
X1066000Y400500D03*
X1063000D03*
X1060000D03*
X1069000D03*
X1072000D03*
X1060984Y418742D03*
X1066000Y433000D03*
X1063000D03*
X1060000D03*
X1069000D03*
X1060000Y439000D03*
X1063000D03*
X1066000D03*
X1060000Y442000D03*
X1063000D03*
X1066000D03*
Y436000D03*
X1063000D03*
X1060000D03*
X1069000D03*
X1072000Y433000D03*
Y436000D03*
X1066000Y448000D03*
X1063000D03*
X1060000D03*
X1066000Y445000D03*
X1063000D03*
X1060000D03*
X1069000Y448000D03*
Y445000D03*
X1072000Y448000D03*
Y445000D03*
X1069000Y480500D03*
Y483500D03*
X1060000Y480500D03*
X1063000D03*
X1066000D03*
X1060000Y483500D03*
X1063000D03*
X1066000D03*
Y486500D03*
X1063000D03*
X1060000D03*
X1072000Y480500D03*
Y483500D03*
X1069000Y492500D03*
Y495500D03*
X1060000Y492500D03*
X1063000D03*
X1066000D03*
X1060000Y495500D03*
X1063000D03*
X1066000D03*
Y489500D03*
X1063000D03*
X1060000D03*
X1072000Y492500D03*
Y495500D03*
X1066500Y541000D03*
X1069500D03*
X1066500Y544000D03*
X1069500D03*
Y538000D03*
X1060498Y575739D03*
X1069500Y547000D03*
Y550000D03*
X1066500Y547000D03*
Y550000D03*
X1069500Y553000D03*
X1094582Y3004D03*
X1074582D03*
X1097100Y35582D03*
Y38582D03*
X1099600D03*
Y35582D03*
X1102100D03*
Y38582D03*
X1096961Y18126D03*
Y21126D03*
X1099461D03*
Y18126D03*
X1101961D03*
Y21126D03*
X1097101Y53737D03*
Y56737D03*
X1099601D03*
Y53737D03*
X1102101D03*
Y56737D03*
X1091000Y99500D03*
X1095100D03*
X1087000Y100000D03*
X1073200Y90900D03*
X1077200D03*
X1073200Y126000D03*
Y128800D03*
Y123200D03*
X1084740Y108000D03*
X1084325Y130197D03*
X1100075Y139925D03*
X1084260Y152600D03*
X1094493Y151856D03*
X1073154Y137800D03*
X1092000Y159500D03*
X1084401Y159260D03*
X1094024Y179500D03*
X1085000Y184575D03*
X1079500D03*
X1085525Y167500D03*
Y171000D03*
Y174500D03*
Y164000D03*
X1087500Y198000D03*
Y201000D03*
X1097500Y203700D03*
X1100000D03*
X1073500Y191500D03*
X1101903Y285019D03*
X1101796Y331894D03*
X1086500Y356000D03*
X1090500Y376500D03*
X1080418Y373600D03*
X1090443Y417343D03*
X1086500Y403500D03*
X1074316Y406925D03*
X1080498Y575739D03*
X1100498D03*
X1114582Y3004D03*
X1125170Y35582D03*
Y38582D03*
X1127670D03*
Y35582D03*
X1130170D03*
Y38582D03*
X1104600Y35582D03*
Y38582D03*
X1107100Y35582D03*
Y38582D03*
X1104461Y18126D03*
Y21126D03*
X1106961Y18126D03*
Y21126D03*
X1130031D03*
Y18126D03*
X1127531D03*
Y21126D03*
X1125031D03*
Y18126D03*
X1104601Y53737D03*
Y56737D03*
X1107101Y53737D03*
Y56737D03*
X1113000Y101240D03*
X1119500Y86000D03*
Y83000D03*
X1123000Y120816D03*
X1126000D03*
X1131500D03*
X1115800Y126600D03*
X1113500Y147500D03*
X1126075Y135973D03*
X1108500Y136500D03*
X1104500Y136524D03*
X1129000Y157000D03*
X1120200D03*
X1115425Y138925D03*
X1119000Y189500D03*
X1111100Y163749D03*
X1110800Y170000D03*
X1120200Y176500D03*
Y166500D03*
X1129000D03*
Y176500D03*
X1108821Y166800D03*
X1125918Y195418D03*
X1129068Y195500D03*
X1106189Y224241D03*
X1118774Y284699D03*
X1112902D03*
X1110019Y284806D03*
X1104786Y284912D03*
X1121657Y284592D03*
X1118667Y331574D03*
X1112795D03*
X1109912Y331681D03*
X1104679Y331787D03*
X1121550Y331467D03*
X1104009Y427245D03*
X1120880Y426925D03*
X1115008D03*
X1112125Y427032D03*
X1106892Y427138D03*
X1123763Y426818D03*
X1103800Y474339D03*
X1106683Y474232D03*
X1111916Y474126D03*
X1114799Y474019D03*
X1120671D03*
X1123554Y473912D03*
X1111452Y544000D03*
Y541000D03*
X1114452Y544000D03*
Y541000D03*
X1111452Y538000D03*
X1120669Y544000D03*
Y541000D03*
X1123669Y544000D03*
Y541000D03*
X1120669Y538000D03*
X1120498Y575739D03*
X1111452Y553000D03*
X1114452Y550000D03*
X1111452D03*
X1114452Y547000D03*
X1111452D03*
X1120669Y553000D03*
X1123669Y550000D03*
X1120669D03*
X1123669Y547000D03*
X1120669D03*
X1154582Y3004D03*
X1134582D03*
X1132670Y35582D03*
X1135170D03*
Y38582D03*
X1132670D03*
X1135031Y21126D03*
Y18126D03*
X1132531Y21126D03*
Y18126D03*
X1132950Y82867D03*
Y85867D03*
X1135450D03*
Y82867D03*
X1137950D03*
X1140450D03*
X1142950D03*
Y85867D03*
X1140450D03*
X1137950D03*
X1155000Y124913D03*
X1159300Y129700D03*
X1141500Y124425D03*
Y120500D03*
X1134500Y120816D03*
X1154000Y151500D03*
X1141500Y134575D03*
X1136300Y161100D03*
X1140000D03*
X1160200Y175982D03*
X1152781Y165719D03*
X1136300Y172300D03*
X1140000D03*
X1140336Y183560D03*
X1158000Y179000D03*
X1138203Y266860D03*
Y260860D03*
Y263860D03*
X1135203Y260860D03*
Y263860D03*
X1138203Y257860D03*
Y254860D03*
X1135203Y257860D03*
Y254860D03*
X1159710Y306037D03*
X1156710D03*
X1159710Y303037D03*
X1156710D03*
X1159710Y300037D03*
X1156710D03*
X1159710Y297037D03*
X1156710D03*
Y294037D03*
X1159710D03*
Y309037D03*
X1156710D03*
X1135403Y302360D03*
Y305360D03*
X1138403Y302360D03*
Y305360D03*
X1135403Y308360D03*
X1138403D03*
X1159710Y312037D03*
X1156710D03*
X1159710Y321037D03*
X1156710D03*
X1159710Y318037D03*
X1156710D03*
X1159710Y315037D03*
X1156710D03*
X1135403Y311360D03*
X1138403D03*
Y314360D03*
Y361979D03*
Y358979D03*
X1135403D03*
X1138403Y355979D03*
X1135403D03*
X1138403Y352979D03*
X1135403D03*
X1138403Y349979D03*
X1135403D03*
X1135190Y396965D03*
X1138190D03*
X1135190Y399965D03*
X1138190D03*
X1135190Y402965D03*
Y405965D03*
X1138190Y402965D03*
Y405965D03*
Y408965D03*
X1159799Y448537D03*
X1156799D03*
X1159799Y445537D03*
X1156799D03*
X1159799Y442537D03*
X1156799D03*
X1159799Y439537D03*
X1156799D03*
Y436537D03*
X1159799D03*
Y454537D03*
X1156799D03*
X1159799Y451537D03*
X1156799D03*
X1135404Y454228D03*
Y451228D03*
Y445228D03*
Y448228D03*
X1138404Y454228D03*
Y451228D03*
Y445228D03*
Y448228D03*
Y457228D03*
X1159799Y457537D03*
X1156799D03*
X1159799Y463537D03*
X1156799D03*
X1159799Y460537D03*
X1156799D03*
X1135622Y485732D03*
Y470732D03*
Y479732D03*
Y476732D03*
Y473732D03*
Y482732D03*
X1138622D03*
Y473732D03*
Y476732D03*
Y479732D03*
Y470732D03*
Y485732D03*
Y467732D03*
X1140498Y575739D03*
X1160498D03*
X1174582Y3004D03*
X1183321Y123652D03*
X1185821D03*
X1188321D03*
Y120652D03*
X1185821D03*
X1183321D03*
X1180821D03*
Y123652D03*
X1178321D03*
Y120652D03*
X1177475Y111500D03*
X1179500Y105500D03*
X1162700Y175959D03*
X1183021Y165952D03*
X1185521D03*
X1188618Y162782D03*
X1185521Y162952D03*
X1183021D03*
X1180521D03*
Y165952D03*
X1177521Y162952D03*
X1167600Y184500D03*
Y180500D03*
X1174500Y214000D03*
Y211000D03*
Y208000D03*
Y205000D03*
X1171500D03*
Y208000D03*
Y211000D03*
Y214000D03*
X1179651Y305942D03*
X1162710Y306037D03*
Y303037D03*
Y300037D03*
Y297037D03*
Y294037D03*
Y309037D03*
X1179651Y309942D03*
X1179411Y334250D03*
Y337750D03*
X1162710Y312037D03*
Y321037D03*
Y318037D03*
Y315037D03*
X1179411Y330750D03*
Y327250D03*
X1180986Y349234D03*
X1179877Y452442D03*
Y448442D03*
X1162799Y448537D03*
Y445537D03*
Y442537D03*
Y439537D03*
Y436537D03*
Y454537D03*
Y451537D03*
Y457537D03*
X1179500Y480250D03*
X1162799Y463537D03*
Y460537D03*
X1179500Y473250D03*
X1181075Y491734D03*
X1180498Y575739D03*
X1214582Y3004D03*
X1194582D03*
X1203887Y306894D03*
X1200887D03*
X1197887D03*
X1203887Y303894D03*
X1200887D03*
X1197887D03*
X1203887Y300894D03*
X1200887D03*
X1197887D03*
X1203887Y297894D03*
X1200887D03*
X1197887D03*
X1203887Y294894D03*
X1200887D03*
X1197887D03*
Y321894D03*
X1200887D03*
X1203887D03*
Y318894D03*
X1200887D03*
X1197887D03*
X1203887Y315894D03*
X1200887D03*
X1197887D03*
X1203887Y312894D03*
X1200887D03*
X1197887D03*
X1203887Y309894D03*
X1200887D03*
X1197887D03*
X1197976Y437394D03*
X1200976D03*
X1203976D03*
X1197976Y440394D03*
X1200976D03*
X1203976D03*
X1197976Y443394D03*
X1200976D03*
X1203976D03*
X1197976Y446394D03*
X1200976D03*
X1203976D03*
X1197976Y449394D03*
X1200976D03*
X1203976D03*
X1197976Y452394D03*
X1200976D03*
X1203976D03*
X1197976Y455394D03*
X1200976D03*
X1203976D03*
X1197976Y464394D03*
X1200976D03*
X1203976D03*
X1197976Y458394D03*
X1200976D03*
X1203976D03*
X1197976Y461394D03*
X1200976D03*
X1203976D03*
X1200498Y575739D03*
X1220498D03*
X1234582Y3004D03*
X1240498Y575739D03*
X1277657Y4128D03*
X1254582Y3004D03*
X1260498Y575739D03*
X1279438Y573806D03*
X1286766Y12634D03*
X1288331Y30962D03*
Y70962D03*
Y50962D03*
Y90962D03*
Y130962D03*
Y110962D03*
Y150962D03*
Y190962D03*
Y170962D03*
Y210962D03*
Y230962D03*
Y270962D03*
Y250962D03*
Y290962D03*
Y330962D03*
Y310962D03*
Y350962D03*
Y390962D03*
Y370962D03*
Y410962D03*
Y450962D03*
Y430962D03*
Y470962D03*
Y510962D03*
Y490962D03*
Y530962D03*
X1287616Y563889D03*
X1288331Y550962D03*
G36*
G01X82800Y111574D02*
G02X82795Y87873I-5J-11850D01*
G02X82790Y111574I0J11851D01*
G01Y109524D01*
G03X82795Y89923I5J-9800D01*
G03X82800Y109524I0J9801D01*
G01Y111574D01*
G37*
G36*
G01Y494055D02*
G02X82795Y470354I-5J-11850D01*
G02X82790Y494055I0J11851D01*
G01Y492005D01*
G03X82795Y472404I5J-9800D01*
G03X82800Y492005I0J9801D01*
G01Y494055D01*
G37*
G54D11*
X19685Y-614173D03*
Y636929D03*
X175000Y100500D03*
X619685Y636929D03*
X877510Y558620D03*
X964460Y16950D03*
X1271654Y-614173D03*
Y636929D03*
G54D30*
X178819Y277204D03*
X193819D03*
X253819D03*
X268819D03*
X336299D03*
X351299D03*
X411299D03*
X426299D03*
X493780D03*
X508780D03*
X568780D03*
X583780D03*
X651261D03*
X666261D03*
X726261D03*
X741261D03*
G54D21*
X147234Y239563D03*
Y232563D03*
X1063500Y124500D03*
Y117500D03*
G54D12*
X72836Y47244D03*
Y535433D03*
X466536Y47244D03*
X860237D03*
X943225Y228000D03*
X985225Y542500D03*
G54D22*
X152016Y331000D03*
Y335500D03*
Y350500D03*
Y346500D03*
X178390Y223523D03*
X213016Y309500D03*
X221516D03*
X230516D03*
X387516D03*
X370016D03*
X378516D03*
X424035Y457500D03*
X537016Y310500D03*
X528016D03*
X546016D03*
X575516Y457500D03*
X685497Y310500D03*
X694497D03*
X703497D03*
X745016Y338500D03*
Y334500D03*
Y324500D03*
Y328500D03*
X732016Y338500D03*
Y328500D03*
X745016Y342500D03*
Y347700D03*
Y353200D03*
Y361500D03*
X775516Y369500D03*
X797516Y357000D03*
Y362000D03*
X824016Y334000D03*
X834516Y323500D03*
Y328000D03*
X937712Y315385D03*
X938212Y347885D03*
X1034516Y139500D03*
X1046516Y125500D03*
X1060016Y130500D03*
X1070516Y114000D03*
X1060016Y134000D03*
X1046516Y133600D03*
X1088016Y167500D03*
Y174500D03*
X1100516Y165000D03*
Y168500D03*
X1088016Y164000D03*
Y171000D03*
X1077359Y363443D03*
X1137516Y196500D03*
Y200500D03*
G54D40*
X223819Y450483D03*
X361000Y303483D03*
X381299Y450483D03*
X397047Y303483D03*
X409000D03*
X538780Y450483D03*
X554528Y303483D03*
X549500Y450483D03*
X712009Y303483D03*
X696261Y450483D03*
X826000Y265983D03*
X831000D03*
X811000Y275983D03*
X811500Y326483D03*
X815500D03*
X823500D03*
X827000Y357983D03*
X832500D03*
X856000Y265983D03*
X846000D03*
X851000D03*
X841000D03*
X836000D03*
X852000Y333983D03*
X847500Y359983D03*
X853000D03*
X874000Y355983D03*
X883000D03*
X904500Y297483D03*
X919500Y280983D03*
X908000Y325483D03*
X924500Y360983D03*
X947000Y299983D03*
X940000D03*
X933000Y280983D03*
X926000D03*
X933196Y315368D03*
Y350868D03*
X1067500Y159483D03*
X1077500Y116983D03*
X1076800Y409983D03*
X1080300D03*
X1114000Y144983D03*
X1104500Y142983D03*
X1146760Y171303D03*
G54D31*
X165539Y539000D03*
X213539D03*
X261539D03*
X323019D03*
X371019D03*
X419019D03*
X480500D03*
X528500D03*
X576500D03*
X637981D03*
X685981D03*
X733981D03*
G54D13*
X74804Y47244D03*
Y535433D03*
X468504Y47244D03*
X862205D03*
X945193Y228000D03*
X987193Y542500D03*
X1196858Y57480D03*
Y521260D03*
G54D23*
X154983Y331000D03*
Y335500D03*
Y350500D03*
Y346500D03*
X181357Y223523D03*
X215983Y309500D03*
X224483D03*
X233483D03*
X390483D03*
X372983D03*
X381483D03*
X427002Y457500D03*
X530983Y310500D03*
X548983D03*
X539983D03*
X578483Y457500D03*
X688464Y310500D03*
X697464D03*
X706464D03*
X734983Y338500D03*
Y328500D03*
X747983Y338500D03*
Y334500D03*
Y324500D03*
Y328500D03*
Y342500D03*
Y347700D03*
Y353200D03*
Y361500D03*
X800483Y357000D03*
Y362000D03*
X778483Y369500D03*
X826983Y334000D03*
X837483Y323500D03*
Y328000D03*
X940679Y315385D03*
X941179Y347885D03*
X1037483Y139500D03*
X1049483Y125500D03*
X1062983Y130500D03*
Y134000D03*
X1049483Y133600D03*
X1073483Y114000D03*
X1090983Y167500D03*
Y174500D03*
Y164000D03*
Y171000D03*
X1080326Y363443D03*
X1103483Y165000D03*
Y168500D03*
X1140483Y196500D03*
Y200500D03*
G54D14*
X19922Y214173D03*
Y367716D03*
G54D50*
X753314Y607542D03*
X766498Y602542D03*
X753420Y635687D03*
X766604Y630687D03*
X766498Y612542D03*
X766604Y640687D03*
X1096017Y607542D03*
X1082833Y602542D03*
Y612542D03*
X1096017Y635687D03*
X1082833Y630687D03*
Y640687D03*
G54D32*
X185224Y539000D03*
X233224D03*
X281224D03*
X342704D03*
X390704D03*
X438704D03*
X500185D03*
X548185D03*
X596185D03*
X657666D03*
X705666D03*
X753666D03*
G54D41*
X268000Y220315D03*
X312500D03*
X357000D03*
X428500D03*
X472500D03*
X516500D03*
X578500D03*
X622500D03*
X666500D03*
X735981D03*
X779981D03*
X823981D03*
G54D51*
X819925Y288000D03*
X822484D03*
X825043D03*
X827602D03*
X830161D03*
X832720D03*
X835280D03*
Y311000D03*
X832720D03*
X830161D03*
X827602D03*
X825043D03*
X822484D03*
X819925D03*
X837839Y288000D03*
X840398D03*
X842957D03*
X845516D03*
X848075D03*
Y311000D03*
X845516D03*
X842957D03*
X840398D03*
X837839D03*
G54D60*
X1049760Y111500D03*
X1057240D03*
X1091240Y135000D03*
X1083760D03*
X1120260Y214500D03*
X1127740D03*
X1146760Y177000D03*
X1154240D03*
G54D24*
X129370Y414500D03*
X150630D03*
X760280Y336484D03*
Y359516D03*
Y356957D03*
Y354398D03*
Y351839D03*
Y349280D03*
Y346720D03*
Y344161D03*
Y341602D03*
Y339043D03*
X782720Y336484D03*
Y339043D03*
Y341602D03*
Y344161D03*
Y346720D03*
Y349280D03*
Y351839D03*
Y354398D03*
Y356957D03*
Y359516D03*
G54D15*
X38780Y232598D03*
Y239291D03*
Y252598D03*
Y259291D03*
Y272598D03*
Y279291D03*
Y292598D03*
Y299291D03*
X48780Y232598D03*
Y239291D03*
Y252598D03*
Y259291D03*
Y272598D03*
Y279291D03*
Y292598D03*
Y299291D03*
G54D42*
X268000Y240000D03*
X312500D03*
X357000D03*
X428500D03*
X472500D03*
X516500D03*
X578500D03*
X622500D03*
X666500D03*
X735981D03*
X779981D03*
X823981D03*
G54D33*
X211000Y26000D03*
X954550Y77250D03*
X1155350Y561140D03*
G54D70*
G01X1024340Y139500D02*
Y122608D01*
X1029900Y117048D01*
Y94900D01*
X1035800Y89000D01*
X1071300D01*
X1073200Y90900D01*
G01X1024340Y139500D02*
Y146600D01*
G01X1077200Y90900D02*
X1073200D01*
G01X1077200D02*
X1106171D01*
X1150092Y109092D01*
X1167600Y126600D01*
Y180500D01*
G01Y184500D02*
Y189560D01*
G01Y180500D02*
Y184500D01*
G01Y197040D02*
Y214900D01*
G54D52*
X831059Y349740D03*
X825941D03*
Y342260D03*
X828500D03*
X831059D03*
X905941Y309260D03*
X908500D03*
X911059D03*
Y316740D03*
X905941D03*
G54D61*
X1077500Y100563D03*
X1081240Y108437D03*
X1073760D03*
X1088000Y156937D03*
X1084260Y149063D03*
X1091740D03*
G54D43*
X247441Y303575D03*
Y300425D03*
X404821Y303575D03*
Y300425D03*
X562402Y303575D03*
Y300425D03*
X719883Y303575D03*
Y300425D03*
G54D34*
X208071Y267204D03*
X200197D03*
X215945D03*
X231693D03*
X223819D03*
X239567D03*
X247441D03*
X357677D03*
X365551D03*
X373425D03*
X389173D03*
X381299D03*
X404921D03*
X397047D03*
X523032D03*
X515158D03*
X530906D03*
X538780D03*
X546654D03*
X562402D03*
X554528D03*
X680513D03*
X672639D03*
X688387D03*
X704135D03*
X696261D03*
X712009D03*
X719883D03*
G54D16*
X33780Y334724D03*
Y324724D03*
X38780Y319724D03*
Y329724D03*
Y339724D03*
X33780Y344724D03*
X38780Y349724D03*
X48780Y319724D03*
Y329724D03*
Y339724D03*
X43780Y314724D03*
Y324724D03*
Y334724D03*
X48780Y349724D03*
X43780Y344724D03*
G54D25*
X127795Y414500D03*
G54D71*
G01X819925Y288000D02*
X818425Y286500D01*
G01X848075Y306500D02*
Y311000D01*
G01X933196Y315460D02*
X933357Y315621D01*
Y322596D01*
G01X941035Y344474D02*
Y340174D01*
G54D35*
X208071Y303484D03*
X239567D03*
X223819Y458484D03*
X251500Y303484D03*
X365551D03*
X381299Y458484D03*
X412019Y450484D03*
X432019Y457484D03*
X523032Y303484D03*
X538780Y458484D03*
X569500Y450484D03*
X589500Y451984D03*
X680513Y303484D03*
X696261Y458484D03*
X724000Y303484D03*
X826000Y275984D03*
X831000D03*
X816000D03*
X821000D03*
X806500Y282484D03*
X819500Y326484D03*
X827500D03*
X821500Y357984D03*
X846000Y275984D03*
X851000D03*
X856000D03*
X841000D03*
X836000D03*
X864500Y355984D03*
X843000Y359984D03*
X875000Y296984D03*
X880000D03*
X870000D03*
X888000Y280984D03*
X877500D03*
X884000D03*
X894500D03*
X875000Y309984D03*
X880000D03*
X870000D03*
X878000Y355984D03*
X869000D03*
X898500Y280984D03*
X909500Y297484D03*
X914500D03*
X909000Y280984D03*
X905000D03*
X915500D03*
X903500Y325484D03*
X909500Y335484D03*
X912500Y325484D03*
X915500Y360984D03*
X920000D03*
X947000Y280984D03*
X940000D03*
X947000Y290984D03*
X940000D03*
X933000D03*
X938000Y360984D03*
X1070000Y188984D03*
X1077000Y184484D03*
X1082500D03*
X1073500Y188984D03*
X1110000Y144984D03*
X1141500Y117484D03*
X1132000Y180484D03*
G54D53*
X852240Y340177D03*
X848500D03*
X844760D03*
Y349823D03*
X852240D03*
X923740Y341177D03*
X920000D03*
X916260D03*
Y350823D03*
X923740D03*
G54D62*
X1093343Y364043D03*
X1092000Y349800D03*
Y344000D03*
X1093343Y369843D03*
X1091000Y397400D03*
Y391600D03*
X1093343Y417343D03*
Y411543D03*
G54D26*
X152205Y414500D03*
G54D44*
X253819Y477204D03*
X411299D03*
X568780D03*
X726261D03*
G54D17*
X33780Y314724D03*
G54D72*
G01X178299Y223523D02*
X177039Y222263D01*
X172712D01*
G01X361000Y303575D02*
Y305975D01*
G01X404821Y300425D02*
X404921D01*
X405013Y300517D01*
X405478D01*
X408536Y303575D01*
X409000D01*
G01X418444Y433500D02*
Y431656D01*
X422500Y427600D01*
X432000D01*
G01D02*
X528300D01*
X606300Y349600D01*
X700700D01*
X702200Y351100D01*
Y356000D01*
G01X549500Y447425D02*
Y445024D01*
G01X589500Y448925D02*
Y446500D01*
G01X742500Y328500D02*
X744925D01*
G01X742500Y324500D02*
X744925D01*
G01X742500Y334500D02*
X744925D01*
G01Y347700D02*
X742500D01*
G01X744925Y353200D02*
X742500D01*
G01X748075Y361500D02*
Y366500D01*
G01X760280Y359516D02*
X758784D01*
X756800Y361500D01*
X748075D01*
G01X803500Y259525D02*
X802000Y261025D01*
Y269500D01*
X804000Y271500D01*
Y279325D01*
X803900Y279425D01*
G01X806500D02*
X803900D01*
G01X800575Y335000D02*
Y338000D01*
G01D02*
Y341000D01*
G01Y330000D02*
Y335000D01*
G01Y346500D02*
X803000D01*
G01X831000Y270500D02*
Y272925D01*
G01X826000Y270525D02*
Y272925D01*
G01X811500Y329000D02*
Y326575D01*
G01X815500Y329000D02*
Y326575D01*
G01X823500Y329000D02*
Y326575D01*
G01X829500Y354925D02*
X832500D01*
G01X811575Y341000D02*
Y344000D01*
G01X841000Y270500D02*
Y272925D01*
G01X846000Y270525D02*
Y272925D01*
G01X851000Y270525D02*
Y272925D01*
G01X836000Y270500D02*
Y272925D01*
G01X856000Y270525D02*
Y272925D01*
G01X852000Y330925D02*
X854825D01*
G01X904500Y292000D02*
Y294425D01*
G01X912000Y332425D02*
X909500D01*
G01X920000Y355525D02*
Y357925D01*
G01X926000Y283475D02*
Y281075D01*
G01X937516Y300075D02*
X940000D01*
G01X947000Y302475D02*
Y300075D01*
G01X943172Y310885D02*
X940771D01*
G01X943885Y352385D02*
X941271D01*
G01X1034425Y139500D02*
X1034500Y139575D01*
Y142000D01*
G01X1068900Y110000D02*
X1070516Y111616D01*
Y113909D01*
X1070425Y114000D01*
G01X1059925Y130500D02*
X1057525D01*
G01X1067500Y156425D02*
X1065000D01*
G01X1059925Y134000D02*
X1057525D01*
G01X1057425Y142000D02*
X1057525Y141900D01*
Y138600D01*
G01X1070000Y191500D02*
Y189075D01*
G01X1081240Y108437D02*
X1081677Y108000D01*
X1084740D01*
G01X1104500Y139925D02*
X1100075D01*
G01X1084260Y149063D02*
Y152600D01*
G01X1095500Y183500D02*
X1100425D01*
G01X1094024Y179500D02*
Y182024D01*
X1095500Y183500D01*
G01X1094024Y179500D02*
X1099000D01*
X1099500Y180000D01*
X1100425D01*
G01X1082500Y184575D02*
X1085000D01*
G01X1079500D02*
X1077000D01*
G01X1087925Y167500D02*
X1085525D01*
G01X1087925Y171000D02*
X1085525D01*
G01X1087925Y174500D02*
X1085525D01*
G01X1087925Y164000D02*
X1085525D01*
G01X1073500Y191500D02*
Y189075D01*
G01X1092000Y338800D02*
Y344000D01*
G01X1077268Y359443D02*
Y363443D01*
G01X1090500Y376500D02*
Y372686D01*
X1093343Y369843D01*
G01X1091100Y386400D02*
Y391500D01*
G01X1093343Y417343D02*
X1090443D01*
G01X1076800Y410075D02*
X1080300D01*
G01X1113937Y150760D02*
Y147937D01*
X1113500Y147500D01*
G01X1110000Y141925D02*
Y138000D01*
X1108500Y136500D01*
G01X1141500Y117575D02*
Y120500D01*
G01X1159300Y129700D02*
X1156997D01*
X1152437Y134260D01*
G01X1154000Y151500D02*
X1153575Y151925D01*
Y154000D01*
G01D02*
Y155067D01*
X1146760Y161882D01*
Y168245D01*
G01X1137425Y196500D02*
Y200500D01*
G01X1133000Y198000D02*
X1134500Y196500D01*
X1137425D01*
G54D36*
X208071Y300517D03*
X239567D03*
X223819Y455517D03*
X251500Y300517D03*
X365551D03*
X381299Y455517D03*
X412019Y447517D03*
X432019Y454517D03*
X523032Y300517D03*
X538780Y455517D03*
X569500Y447517D03*
X589500Y449017D03*
X680513Y300517D03*
X696261Y455517D03*
X724000Y300517D03*
X826000Y273017D03*
X831000D03*
X816000D03*
X821000D03*
X806500Y279517D03*
X819500Y323517D03*
X827500D03*
X821500Y355017D03*
X846000Y273017D03*
X851000D03*
X856000D03*
X841000D03*
X836000D03*
X864500Y353017D03*
X843000Y357017D03*
X888000Y278017D03*
X877500D03*
X884000D03*
X894500D03*
X875000Y307017D03*
X880000D03*
X875000Y294017D03*
X880000D03*
X870000Y307017D03*
Y294017D03*
X878000Y353017D03*
X869000D03*
X898500Y278017D03*
X909000D03*
X905000D03*
X915500D03*
X909500Y294517D03*
X914500D03*
X903500Y322517D03*
X909500Y332517D03*
X912500Y322517D03*
X915500Y358017D03*
X920000D03*
X947000Y278017D03*
X940000D03*
X947000Y288017D03*
X940000D03*
X933000D03*
X938000Y358017D03*
X1070000Y186017D03*
X1077000Y181517D03*
X1082500D03*
X1073500Y186017D03*
X1110000Y142017D03*
X1141500Y114517D03*
X1132000Y177517D03*
G54D18*
X60630Y99724D03*
Y482205D03*
X108858Y99724D03*
Y482205D03*
G54D54*
X865000Y338900D03*
Y318100D03*
X880000Y338900D03*
X875000D03*
X870000D03*
Y318100D03*
X875000D03*
X880000D03*
G54D63*
X1086243Y343943D03*
X1080443D03*
X1086243Y352443D03*
X1080443D03*
X1086243Y392500D03*
X1080443D03*
X1086243Y399943D03*
X1080443D03*
G54D45*
X296752Y129685D03*
Y139685D03*
Y149685D03*
X331752Y129685D03*
X306752D03*
X331752Y139685D03*
Y149685D03*
Y159685D03*
X306752Y139685D03*
Y149685D03*
Y159685D03*
X341752Y129685D03*
Y139685D03*
Y149685D03*
Y159685D03*
X376752Y129685D03*
X366752D03*
X376752Y139685D03*
Y149685D03*
Y159685D03*
X366752Y139685D03*
Y149685D03*
Y159685D03*
X411752Y129685D03*
X401752D03*
X411752Y139685D03*
Y149685D03*
Y159685D03*
X401752Y139685D03*
Y149685D03*
Y159685D03*
X446752Y129685D03*
X436752D03*
X446752Y139685D03*
Y149685D03*
Y159685D03*
X436752Y139685D03*
Y149685D03*
Y159685D03*
X481752Y129685D03*
X471752D03*
X481752Y139685D03*
Y149685D03*
Y159685D03*
X471752Y139685D03*
Y149685D03*
Y159685D03*
X712559Y129408D03*
Y119408D03*
Y149408D03*
Y139408D03*
X722559Y129408D03*
Y119408D03*
X747559Y129408D03*
Y119408D03*
X722559Y149408D03*
Y139408D03*
X747559Y149408D03*
Y139408D03*
X757559Y129408D03*
Y119408D03*
Y149408D03*
Y139408D03*
X782559Y129408D03*
Y119408D03*
X792559Y129408D03*
Y119408D03*
X782559Y149408D03*
Y139408D03*
X792559Y149408D03*
Y139408D03*
X812559Y119408D03*
Y129408D03*
X822559Y119408D03*
Y129408D03*
X832559Y119408D03*
Y129408D03*
X812559Y139408D03*
Y149408D03*
X822559Y139408D03*
Y149408D03*
X832559Y139408D03*
X852559Y129408D03*
Y119408D03*
X862559Y129408D03*
Y119408D03*
X852559Y149408D03*
Y139408D03*
X862559Y149408D03*
Y139408D03*
X887559Y129408D03*
Y119408D03*
Y149408D03*
Y139408D03*
X897559Y129408D03*
Y119408D03*
X922559Y129408D03*
Y119408D03*
X897559Y149408D03*
Y139408D03*
X922559Y149408D03*
Y139408D03*
X932559Y129408D03*
Y119408D03*
Y149408D03*
Y139408D03*
X1226024Y221929D03*
X1236024D03*
X1246024D03*
X1226024Y231929D03*
X1236024D03*
X1246024D03*
X1226024Y256929D03*
X1236024D03*
X1246024D03*
X1226024Y266929D03*
X1236024D03*
X1246024D03*
X1236024Y286929D03*
X1246024D03*
X1226024Y306929D03*
X1236024D03*
X1246024D03*
X1226024Y316929D03*
X1236024D03*
X1246024D03*
X1226024Y341929D03*
X1236024D03*
X1246024D03*
X1226024Y351929D03*
X1236024D03*
X1246024D03*
X1256024Y221929D03*
Y231929D03*
Y256929D03*
Y266929D03*
Y286929D03*
Y306929D03*
Y316929D03*
Y341929D03*
Y351929D03*
G54D27*
G01X208071Y267204D02*
Y300425D01*
G01X247441D02*
X243600Y296584D01*
Y271045D01*
X247441Y267204D01*
G01X216075Y309500D02*
X218500D01*
G01X224575D02*
X226975D01*
G01X233575D02*
X235975D01*
G01X716100Y255987D02*
X695443D01*
X693600Y257830D01*
X332670D01*
X320000Y270500D01*
Y297500D01*
X313925Y303575D01*
X251500D01*
G01Y300425D02*
X247441D01*
G01X365551Y267204D02*
Y300425D01*
G01X373075Y309500D02*
X375500D01*
G01X381575D02*
X383975D01*
G01X390575D02*
X392975D01*
G01X404921Y267204D02*
X401000Y271125D01*
Y292500D01*
X404821Y296321D01*
Y300425D01*
G01Y303575D02*
Y305875D01*
X404921Y305975D01*
G01X409000Y300425D02*
X501055D01*
X522040Y321410D01*
X555590D01*
X557900Y319100D01*
Y303400D01*
X560875Y300425D01*
X562402D01*
G01X409000Y303575D02*
X499575D01*
X520530Y324530D01*
X580570D01*
X588400Y316700D01*
X716800D01*
X724500Y309000D01*
Y304075D01*
X724000Y303575D01*
G01X523032Y267204D02*
Y300425D01*
G01X531075Y310500D02*
X533475D01*
G01X562402Y300425D02*
Y296401D01*
X558500Y292499D01*
Y271106D01*
X562402Y267204D01*
G01X540075Y310500D02*
X542475D01*
G01X549075D02*
X551475D01*
G01X575925Y425500D02*
Y392575D01*
X612500Y356000D01*
X702200D01*
G01X575925Y433500D02*
Y425500D01*
G01X680513Y267204D02*
Y300425D01*
G01X719883D02*
X716000Y296542D01*
Y271087D01*
X719883Y267204D01*
G01X688556Y310500D02*
X690956D01*
G01X697556D02*
X699956D01*
G01X706556D02*
X708956D01*
G01X724000Y300425D02*
Y294500D01*
G01Y300425D02*
X719883D01*
G01X803000Y357000D02*
X800575D01*
G01Y352000D02*
Y357000D01*
G01X802975Y362000D02*
X800575D01*
G01X808500Y276075D02*
X811000D01*
G01X818425Y286500D02*
X816499D01*
X811000Y281001D01*
Y276075D01*
G01X832500Y354925D02*
Y353001D01*
X831059Y351560D01*
Y349740D01*
G01X827000Y360475D02*
Y358075D01*
G01X839692Y329592D02*
X838100Y328000D01*
X837575D01*
G01X847500Y360075D02*
X850500D01*
G01Y356925D02*
X853000D01*
G01D02*
Y354501D01*
X852240Y353741D01*
Y349823D01*
G01X870000Y304525D02*
Y306925D01*
G01X875000Y304525D02*
Y306925D01*
G01X880000Y304525D02*
Y306925D01*
G01X874000Y358475D02*
Y356075D01*
G01X883000Y352925D02*
X885500D01*
G01X880000Y338900D02*
Y349925D01*
X883000Y352925D01*
G01X912500Y322425D02*
X912416D01*
X911059Y321068D01*
Y316740D01*
G01X915000Y322425D02*
X912500D01*
G01X923740Y350823D02*
Y354864D01*
X924500Y355624D01*
Y357925D01*
G01X930500Y315460D02*
X933196D01*
G01X924500Y357925D02*
X927000D01*
G01X1095575Y358640D02*
Y354000D01*
G01Y406310D02*
Y401500D01*
G01X1193411Y328750D02*
X1188470D01*
X1182480Y322760D01*
Y308771D01*
X1179651Y305942D01*
G01Y309942D02*
X1180180Y310471D01*
Y322729D01*
X1174159Y328750D01*
X1165070D01*
G01X1179877Y452442D02*
X1180080Y452645D01*
Y464671D01*
X1173501Y471250D01*
X1165190D01*
G01X1179877Y448442D02*
X1182380Y450945D01*
Y465010D01*
X1188620Y471250D01*
X1193840D01*
X165350Y220098D03*
X162850D03*
Y227185D03*
Y230728D03*
X165350Y223642D03*
Y227185D03*
Y230728D03*
X162850Y223642D03*
G54D73*
G01X782720Y336484D02*
X786500D01*
G54D28*
X181388Y227723D03*
X215984Y300500D03*
X224484D03*
X233484D03*
X224484Y305000D03*
X233484D03*
X215984D03*
X390484Y300500D03*
X372984D03*
X381484D03*
X390484Y305000D03*
X381484D03*
X372984D03*
X421503Y433500D03*
X530984Y300500D03*
Y305500D03*
X539984Y300500D03*
X548984D03*
X539984Y305500D03*
X548984D03*
X578984Y433500D03*
X688465Y300500D03*
X697465D03*
X706465D03*
X688465Y305500D03*
X697465D03*
X706465D03*
X800484Y330000D03*
Y335000D03*
Y341000D03*
Y346500D03*
Y352000D03*
X811484Y341000D03*
Y357000D03*
Y362000D03*
X837484Y332500D03*
X940484Y306500D03*
X940680Y310885D03*
X941180Y352385D03*
X1049484Y129000D03*
X1060484Y142000D03*
X1049484Y137500D03*
X1044984Y151000D03*
X1080327Y359443D03*
X1103484Y180000D03*
Y183500D03*
X1140779Y143734D03*
X1153484Y154000D03*
G54D55*
X866000Y370200D03*
Y381800D03*
X847000Y370200D03*
Y381800D03*
X856500Y370200D03*
Y381800D03*
X885000Y370200D03*
Y381800D03*
X894500Y370200D03*
Y381800D03*
X875500Y370200D03*
Y381800D03*
X904000Y370200D03*
Y381800D03*
X923500Y370200D03*
Y381800D03*
X913500Y370200D03*
Y381800D03*
X933000Y370200D03*
Y381800D03*
X942500Y370200D03*
Y381800D03*
X952000Y370200D03*
Y381800D03*
G54D64*
X1086343Y368243D03*
Y359643D03*
Y415743D03*
Y407143D03*
G54D46*
X296752Y159685D03*
X832559Y149408D03*
X1226024Y286929D03*
G54D37*
X193819Y477204D03*
X223819D03*
X351299D03*
X381299D03*
X508780D03*
X538780D03*
X666261D03*
X696261D03*
G54D19*
X60600Y335500D03*
X68403Y323700D03*
X69745Y350042D03*
X154840Y244730D03*
X128500Y426000D03*
X178265Y213443D03*
X175976Y218775D03*
X166068Y238749D03*
X173869Y228168D03*
X178329Y232900D03*
X160017Y237764D03*
X185954Y226083D03*
X171302Y333471D03*
X163247Y335500D03*
X179400Y326800D03*
X183539Y518000D03*
Y498000D03*
X171939D03*
Y518000D03*
X246000Y238500D03*
X231539Y518000D03*
Y498000D03*
X219939D03*
Y518000D03*
X267939Y498000D03*
Y518000D03*
X279539D03*
Y498000D03*
X329419D03*
Y518000D03*
X341019D03*
Y498000D03*
X369925Y287357D03*
X378479Y314111D03*
X389019Y518000D03*
Y498000D03*
X377419D03*
Y518000D03*
X402000Y238000D03*
X398500Y247000D03*
X421594Y438360D03*
X432000Y427600D03*
X437019Y518000D03*
Y498000D03*
X425419D03*
Y518000D03*
X498500Y498000D03*
Y518000D03*
X486900Y498000D03*
Y518000D03*
X535000Y295900D03*
X534900Y498000D03*
Y518000D03*
X544500Y450575D03*
X546500Y498000D03*
Y518000D03*
X575925Y425500D03*
X578984Y438000D03*
X594500Y498000D03*
Y518000D03*
X582900D03*
Y498000D03*
X605600Y448446D03*
X647975Y37000D03*
X660200Y56800D03*
X652300D03*
X655981Y518000D03*
Y498000D03*
X644381Y518000D03*
Y498000D03*
X684525Y32500D03*
X690075Y39500D03*
X683600Y56800D03*
X676000D03*
X668100D03*
X680400Y310500D03*
X703740Y41000D03*
X707000Y32000D03*
X694425Y29500D03*
X693000Y56600D03*
X706000Y61975D03*
X703740Y54118D03*
X703981Y518000D03*
Y498000D03*
X692381Y518000D03*
Y498000D03*
X740381Y518000D03*
Y498000D03*
X761560Y38500D03*
Y30000D03*
Y55500D03*
Y47000D03*
Y64000D03*
X753500Y326000D03*
X753020Y338500D03*
X754000Y356957D03*
X753550Y344161D03*
X759000Y365500D03*
X775425Y364500D03*
X753000Y366500D03*
X766240Y366446D03*
X751981Y498000D03*
Y518000D03*
X784855Y265184D03*
X790000Y259612D03*
X794900Y265979D03*
X798500Y272600D03*
X806000Y265075D03*
X790730Y351839D03*
X791000Y362000D03*
X791563Y342917D03*
X833500Y281000D03*
X815500Y281500D03*
X823206Y281207D03*
X811000Y286000D03*
X815000Y318500D03*
X827500D03*
X833500Y337000D03*
X819500Y336500D03*
X842075Y158924D03*
X843000Y167000D03*
X849500Y281500D03*
X841409Y280566D03*
X853000Y303500D03*
X842600Y317600D03*
X860000Y348000D03*
X879038Y271576D03*
X890676Y272620D03*
X871049Y266946D03*
X872500Y301906D03*
X871000Y348000D03*
X869000Y360500D03*
X903939Y272864D03*
X920899Y272824D03*
X913078Y271503D03*
X915143Y288612D03*
X914500Y303911D03*
X905819Y302819D03*
X898500Y285686D03*
X920000Y320135D03*
X910992Y361075D03*
X930086Y272986D03*
X945201Y272656D03*
X937676Y268356D03*
X932500Y305385D03*
X952000Y286500D03*
X945500Y319000D03*
X942546Y357925D03*
X1043500Y111500D03*
X1034500Y145000D03*
X1039500Y134500D03*
X1043936Y145745D03*
X1019040Y157310D03*
X1022168Y161783D03*
X1017909Y151424D03*
X1024340Y139500D03*
X1016614Y190267D03*
X1039016Y189075D03*
Y183027D03*
X1022000Y171200D03*
X1019700Y166600D03*
X1063500Y111500D03*
X1049356Y143900D03*
X1054500Y148500D03*
X1073154Y140800D03*
X1057500Y155877D03*
X1062500Y191500D03*
X1067701Y270442D03*
X1061600Y276242D03*
X1067679Y317942D03*
X1061600Y323742D03*
X1067707Y365442D03*
X1067531Y412942D03*
X1067730Y460352D03*
X1061600Y466242D03*
X1067866Y507629D03*
X1061600Y513742D03*
X1066500Y538000D03*
Y553000D03*
X1092000Y82500D03*
X1095500Y117075D03*
X1085300Y114016D03*
X1082000Y143600D03*
X1094500Y143144D03*
X1102000Y148000D03*
X1098500Y156937D03*
X1095500Y183500D03*
X1096000Y170500D03*
Y165000D03*
X1092000Y338800D03*
X1095575Y358640D03*
X1091100Y386400D03*
X1095575Y406310D03*
X1130125Y135940D03*
X1121238Y144500D03*
X1120524Y138457D03*
X1123500Y187000D03*
X1108000Y172000D03*
X1113368Y171619D03*
X1113129Y165719D03*
X1114500Y188700D03*
X1131476Y169294D03*
X1133000Y198000D03*
X1117206Y231741D03*
X1117290Y224241D03*
X1106106Y231741D03*
X1114452Y538000D03*
X1123669D03*
X1114452Y553000D03*
X1123669D03*
X1158200Y137700D03*
X1150425Y147401D03*
X1143490Y183560D03*
X1152500Y186500D03*
X1135203Y266860D03*
X1135403Y314360D03*
Y361979D03*
X1135190Y408965D03*
X1135404Y457228D03*
X1135622Y467732D03*
X1188600Y166000D03*
X1177521Y165952D03*
X1165070Y328750D03*
X1193411D03*
X1177836Y349234D03*
X1165190Y471250D03*
X1179500Y476750D03*
Y469750D03*
X1177925Y491734D03*
X1193840Y471250D03*
X1271500Y282000D03*
X1270000Y290000D03*
G54D74*
G01X161737Y535198D02*
X165539Y539000D01*
G01D02*
X169341Y542802D01*
G01X161737D02*
X165539Y539000D01*
G01D02*
X169341Y535198D01*
G01X209737D02*
X213539Y539000D01*
G01D02*
X217341Y542802D01*
G01X209737D02*
X213539Y539000D01*
G01D02*
X217341Y535198D01*
G01X268000Y240000D02*
X271702Y236298D01*
G01X264298Y243702D02*
X268000Y240000D01*
G01D02*
X271702Y243702D01*
G01X264298Y236298D02*
X268000Y240000D01*
G01X257737Y535198D02*
X261539Y539000D01*
G01D02*
X265341Y542802D01*
G01X257737D02*
X261539Y539000D01*
G01D02*
X265341Y535198D01*
G01X312500Y240000D02*
X316202Y236298D01*
G01X308798Y243702D02*
X312500Y240000D01*
G01D02*
X316202Y243702D01*
G01X308798Y236298D02*
X312500Y240000D01*
G01X319217Y535198D02*
X323019Y539000D01*
G01D02*
X326821Y542802D01*
G01X319217D02*
X323019Y539000D01*
G01D02*
X326821Y535198D01*
G01X357000Y240000D02*
X360702Y236298D01*
G01X353298Y243702D02*
X357000Y240000D01*
G01D02*
X360702Y243702D01*
G01X353298Y236298D02*
X357000Y240000D01*
G01X367217Y535198D02*
X371019Y539000D01*
G01D02*
X374821Y542802D01*
G01X367217D02*
X371019Y539000D01*
G01D02*
X374821Y535198D01*
G01X415217D02*
X419019Y539000D01*
G01D02*
X422821Y542802D01*
G01X415217D02*
X419019Y539000D01*
G01D02*
X422821Y535198D01*
G01X428500Y240000D02*
X432202Y236298D01*
G01X424798Y243702D02*
X428500Y240000D01*
G01D02*
X432202Y243702D01*
G01X424798Y236298D02*
X428500Y240000D01*
G01X472500D02*
X476202Y236298D01*
G01X468798Y243702D02*
X472500Y240000D01*
G01D02*
X476202Y243702D01*
G01X468798Y236298D02*
X472500Y240000D01*
G01X476698Y535198D02*
X480500Y539000D01*
G01D02*
X484302Y542802D01*
G01X476698D02*
X480500Y539000D01*
G01D02*
X484302Y535198D01*
G01X516500Y240000D02*
X520202Y236298D01*
G01X512798Y243702D02*
X516500Y240000D01*
G01D02*
X520202Y243702D01*
G01X512798Y236298D02*
X516500Y240000D01*
G01X524698Y535198D02*
X528500Y539000D01*
G01D02*
X532302Y542802D01*
G01X524698D02*
X528500Y539000D01*
G01D02*
X532302Y535198D01*
G01X578500Y240000D02*
X582202Y236298D01*
G01X574798Y243702D02*
X578500Y240000D01*
G01D02*
X582202Y243702D01*
G01X574798Y236298D02*
X578500Y240000D01*
G01X572698Y535198D02*
X576500Y539000D01*
G01D02*
X580302Y542802D01*
G01X572698D02*
X576500Y539000D01*
G01D02*
X580302Y535198D01*
G01X622500Y240000D02*
X626202Y236298D01*
G01X618798Y243702D02*
X622500Y240000D01*
G01D02*
X626202Y243702D01*
G01X618798Y236298D02*
X622500Y240000D01*
G01X634179Y535198D02*
X637981Y539000D01*
G01D02*
X641783Y542802D01*
G01X634179D02*
X637981Y539000D01*
G01D02*
X641783Y535198D01*
G01X666500Y240000D02*
X670202Y236298D01*
G01X662798Y243702D02*
X666500Y240000D01*
G01D02*
X670202Y243702D01*
G01X662798Y236298D02*
X666500Y240000D01*
G01X682179Y535198D02*
X685981Y539000D01*
G01D02*
X689783Y542802D01*
G01X682179D02*
X685981Y539000D01*
G01D02*
X689783Y535198D01*
G01X735981Y240000D02*
X739683Y236298D01*
G01X732279Y243702D02*
X735981Y240000D01*
G01D02*
X739683Y243702D01*
G01X732279Y236298D02*
X735981Y240000D01*
G01X730179Y535198D02*
X733981Y539000D01*
G01D02*
X737783Y542802D01*
G01X730179D02*
X733981Y539000D01*
G01D02*
X737783Y535198D01*
G01X776279Y243702D02*
X779981Y240000D01*
G01X776279Y236298D02*
X779981Y240000D01*
G01D02*
X783683Y236298D01*
G01X779981Y240000D02*
X783683Y243702D01*
G01X820279Y236298D02*
X823981Y240000D01*
G01D02*
X827683Y243702D01*
G01X820279D02*
X823981Y240000D01*
G01D02*
X827683Y236298D01*
G01X1077069Y359642D02*
X1061600D01*
G01X1076800Y410075D02*
X1068133Y418742D01*
X1060984D01*
G01X1093343Y364043D02*
X1090543D01*
X1086343Y368243D01*
G01X1093343Y364043D02*
X1095575Y361811D01*
Y358640D01*
G01X1093343Y411543D02*
X1090543D01*
X1086343Y415743D01*
G01X1093343Y411543D02*
X1095575Y409311D01*
Y406310D01*
G54D29*
X178421Y227723D03*
X213017Y300500D03*
Y305000D03*
X221517Y300500D03*
X230517D03*
X221517Y305000D03*
X230517D03*
X387517Y300500D03*
X370017D03*
X378517D03*
X387517Y305000D03*
X378517D03*
X370017D03*
X418536Y433500D03*
X528017Y300500D03*
X537017D03*
Y305500D03*
X528017D03*
X546017Y300500D03*
Y305500D03*
X576017Y433500D03*
X685498Y300500D03*
Y305500D03*
X694498Y300500D03*
X703498D03*
X694498Y305500D03*
X703498D03*
X797517Y330000D03*
Y335000D03*
Y341000D03*
Y346500D03*
Y352000D03*
X834517Y332500D03*
X808517Y341000D03*
Y357000D03*
Y362000D03*
X937517Y306500D03*
X937713Y310885D03*
X938213Y352385D03*
X1042017Y151000D03*
X1046517Y129000D03*
X1057517Y142000D03*
X1046517Y137500D03*
X1100517Y180000D03*
Y183500D03*
X1077360Y359443D03*
X1137812Y143734D03*
X1150517Y154000D03*
G54D56*
X933357Y322596D03*
X935916D03*
X938476D03*
X941035D03*
Y340174D03*
X938476D03*
X935916D03*
X933357D03*
G54D47*
X418582Y448000D03*
X426456Y444260D03*
Y451740D03*
X576063Y448000D03*
X583937Y444260D03*
Y451740D03*
X890063Y298740D03*
Y291260D03*
X897937Y295000D03*
X908937Y345500D03*
X901063Y349240D03*
Y341760D03*
X1106063Y154500D03*
X1113937Y150760D03*
Y158240D03*
X1144563Y138000D03*
X1152437Y134260D03*
Y141740D03*
G54D65*
X1092425Y354000D03*
X1095575D03*
X1092425Y401500D03*
X1095575D03*
G36*
G01X236452Y129690D02*
G02X249252Y116884I12800J-5D01*
G02X236452Y129680I0J12801D01*
G01X240952D01*
G03X249252Y137985I8300J5D01*
G03X240952Y129690I0J-8300D01*
G01X236452D01*
G37*
G36*
G01X516452D02*
G02X529252Y116884I12800J-5D01*
G02X516452Y129680I0J12801D01*
G01X520952D01*
G03X529252Y137985I8300J5D01*
G03X520952Y129690I0J-8300D01*
G01X516452D01*
G37*
G36*
G01X1213224Y174434D02*
G02X1226024Y161628I12800J-5D01*
G02X1213224Y174424I0J12801D01*
G01X1217724D01*
G03X1226024Y182729I8300J5D01*
G03X1217724Y174434I0J-8300D01*
G01X1213224D01*
G37*
G36*
G01Y399434D02*
G02X1226024Y386628I12800J-5D01*
G02X1213224Y399424I0J12801D01*
G01X1217724D01*
G03X1226024Y407729I8300J5D01*
G03X1217724Y399434I0J-8300D01*
G01X1213224D01*
G37*
G54D75*
G01X1092000Y82500D02*
X1097015D01*
X1153320Y105820D01*
X1171650Y124150D01*
Y184100D01*
X1182750Y195200D01*
X1186700D01*
X1213300Y221800D01*
Y274205D01*
X1226024Y286929D01*
G54D48*
X563000Y453240D03*
Y445760D03*
X1110500Y117260D03*
Y124740D03*
X1148000Y206260D03*
Y213740D03*
X1140500Y206260D03*
Y213740D03*
X1155500Y206260D03*
Y213740D03*
X1167600Y189560D03*
Y197040D03*
G54D66*
X1144019Y149734D03*
X1134571D03*
G54D39*
X223819Y447516D03*
X361000Y300516D03*
X381299Y447516D03*
X397047Y300516D03*
X409000D03*
X538780Y447516D03*
X554528Y300516D03*
X549500Y447516D03*
X712009Y300516D03*
X696261Y447516D03*
X826000Y263016D03*
X831000D03*
X811000Y273016D03*
X811500Y323516D03*
X815500D03*
X823500D03*
X827000Y355016D03*
X832500D03*
X856000Y263016D03*
X846000D03*
X851000D03*
X841000D03*
X836000D03*
X852000Y331016D03*
X847500Y357016D03*
X853000D03*
X874000Y353016D03*
X883000D03*
X919500Y278016D03*
X904500Y294516D03*
X908000Y322516D03*
X924500Y358016D03*
X933000Y278016D03*
X926000D03*
X947000Y297016D03*
X940000D03*
X933196Y312401D03*
Y347901D03*
X1067500Y156516D03*
X1077500Y114016D03*
X1076800Y407016D03*
X1080300D03*
X1114000Y142016D03*
X1104500Y140016D03*
X1146760Y168336D03*
G54D57*
X1011000Y98000D03*
X1151000Y90400D03*
G54D76*
G01X268819Y277204D02*
X273864Y282249D01*
G01X268819Y277204D02*
X263774Y282249D01*
G01X268819Y277204D02*
X263774Y272159D01*
G01X268819Y277204D02*
X273864Y272159D01*
G01X253819Y277204D02*
X258864Y282249D01*
G01X253819Y277204D02*
X258864Y272159D01*
G01X250753Y286727D02*
X248798Y284772D01*
Y282225D01*
X253819Y277204D01*
G01D02*
X248774Y272159D01*
G01X248467Y471852D02*
X253819Y477204D01*
G01D02*
X259171Y482556D01*
G01X248467D02*
X253819Y477204D01*
G01D02*
X259171Y471852D01*
G01X405947D02*
X411299Y477204D01*
G01D02*
X416651Y482556D01*
G01X405947D02*
X411299Y477204D01*
G01D02*
X416651Y471852D01*
G01X563428D02*
X568780Y477204D01*
G01D02*
X574132Y482556D01*
G01X563428D02*
X568780Y477204D01*
G01D02*
X574132Y471852D01*
G01X720909D02*
X726261Y477204D01*
G01D02*
X731613Y482556D01*
G01X720909D02*
X726261Y477204D01*
G01D02*
X731613Y471852D01*
G36*
G01X665064Y162208D02*
G02X665059Y136607I-5J-12800D01*
G02X665054Y162208I0J12801D01*
G01Y157708D01*
G03X665059Y141107I5J-8300D01*
G03X665064Y157708I0J8301D01*
G01Y162208D01*
G37*
G36*
G01X980064D02*
G02X980059Y136607I-5J-12800D01*
G02X980054Y162208I0J12801D01*
G01Y157708D01*
G03X980059Y141107I5J-8300D01*
G03X980064Y157708I0J8301D01*
G01Y162208D01*
G37*
G54D58*
X1011000Y118000D03*
Y108000D03*
X1161000Y90400D03*
X1171000D03*
G54D67*
X1183561Y130467D03*
Y156451D03*
G54D77*
G01X-297025Y-1013390D02*
Y1828909D01*
X3691357D01*
Y-1013390D01*
X-297025D01*
G01X4093Y-769672D02*
Y-844672D01*
X504093D01*
Y-769672D01*
X4093D01*
G01X16093Y-834672D02*
Y-839672D01*
G01X14636Y-834672D02*
X17550D01*
G01X22460Y-839672D02*
X19926D01*
Y-834672D01*
X22460D01*
G01X21446Y-837089D02*
X19926D01*
G01X25026Y-834672D02*
Y-839672D01*
X27560D01*
G01X31393Y-839839D02*
X31266Y-839755D01*
Y-839589D01*
X31393Y-839505D01*
X31520Y-839589D01*
Y-839755D01*
X31393Y-839839D01*
G01Y-837589D02*
X31266Y-837505D01*
Y-837339D01*
X31393Y-837255D01*
X31520Y-837339D01*
Y-837505D01*
X31393Y-837589D01*
G01X36176Y-841339D02*
X35543Y-840505D01*
X35226Y-839672D01*
Y-836339D01*
X35543Y-835505D01*
X36176Y-834672D01*
G01X41593D02*
X41086Y-834839D01*
X40706Y-835255D01*
X40453Y-835755D01*
X40263Y-836422D01*
X40200Y-837172D01*
X40263Y-837922D01*
X40453Y-838589D01*
X40706Y-839089D01*
X41086Y-839505D01*
X41593Y-839672D01*
X42100Y-839505D01*
X42480Y-839089D01*
X42733Y-838589D01*
X42923Y-837922D01*
X42986Y-837172D01*
X42923Y-836422D01*
X42733Y-835755D01*
X42480Y-835255D01*
X42100Y-834839D01*
X41593Y-834672D01*
G01X45300Y-838672D02*
X45680Y-839255D01*
X46186Y-839589D01*
X46756Y-839672D01*
X47263Y-839589D01*
X47770Y-839172D01*
X48086Y-838672D01*
X48150Y-838172D01*
X48023Y-837589D01*
X47580Y-837172D01*
X47136Y-837005D01*
X46566D01*
G01X47136D02*
X47516Y-836755D01*
X47833Y-836339D01*
X47960Y-835839D01*
X47833Y-835339D01*
X47516Y-834922D01*
X46946Y-834672D01*
X46376Y-834755D01*
X45806Y-835089D01*
G01X52110Y-841339D02*
X52743Y-840505D01*
X53060Y-839672D01*
Y-836339D01*
X52743Y-835505D01*
X52110Y-834672D01*
G01X55500Y-838672D02*
X55880Y-839255D01*
X56386Y-839589D01*
X56956Y-839672D01*
X57463Y-839589D01*
X57970Y-839172D01*
X58286Y-838672D01*
X58350Y-838172D01*
X58223Y-837589D01*
X57780Y-837172D01*
X57336Y-837005D01*
X56766D01*
G01X57336D02*
X57716Y-836755D01*
X58033Y-836339D01*
X58160Y-835839D01*
X58033Y-835339D01*
X57716Y-834922D01*
X57146Y-834672D01*
X56576Y-834755D01*
X56006Y-835089D01*
G01X60790Y-835505D02*
X61170Y-835005D01*
X61613Y-834755D01*
X62120Y-834672D01*
X62753Y-834839D01*
X63196Y-835255D01*
X63323Y-835755D01*
X63260Y-836255D01*
X63006Y-836672D01*
X61740Y-837505D01*
X61170Y-838089D01*
X60790Y-838922D01*
X60663Y-839672D01*
X63323D01*
G01X66966D02*
X67093Y-838589D01*
X67283Y-837672D01*
X67536Y-836839D01*
X67853Y-835922D01*
X68360Y-834672D01*
X65826D01*
G01X71370Y-838005D02*
X73016D01*
G01X76090Y-835505D02*
X76470Y-835005D01*
X76913Y-834755D01*
X77420Y-834672D01*
X78053Y-834839D01*
X78496Y-835255D01*
X78623Y-835755D01*
X78560Y-836255D01*
X78306Y-836672D01*
X77040Y-837505D01*
X76470Y-838089D01*
X76090Y-838922D01*
X75963Y-839672D01*
X78623D01*
G01X81000Y-838672D02*
X81380Y-839255D01*
X81886Y-839589D01*
X82456Y-839672D01*
X82963Y-839589D01*
X83470Y-839172D01*
X83786Y-838672D01*
X83850Y-838172D01*
X83723Y-837589D01*
X83280Y-837172D01*
X82836Y-837005D01*
X82266D01*
G01X82836D02*
X83216Y-836755D01*
X83533Y-836339D01*
X83660Y-835839D01*
X83533Y-835339D01*
X83216Y-834922D01*
X82646Y-834672D01*
X82076Y-834755D01*
X81506Y-835089D01*
G01X88253Y-839672D02*
Y-834672D01*
X85910Y-838255D01*
X89076D01*
G01X91200Y-838922D02*
X91580Y-839339D01*
X92023Y-839589D01*
X92593Y-839672D01*
X93163Y-839505D01*
X93606Y-839172D01*
X93923Y-838589D01*
X93986Y-837922D01*
X93860Y-837255D01*
X93543Y-836839D01*
X93100Y-836505D01*
X92656Y-836422D01*
X92213Y-836505D01*
X91643Y-836839D01*
X91833Y-834672D01*
X93543D01*
G01X101590Y-839672D02*
Y-834672D01*
X103996D01*
G01X103110Y-837089D02*
X101590D01*
G01X106310Y-839672D02*
X107893Y-834672D01*
X109476Y-839672D01*
G01X108906Y-837922D02*
X106880D01*
G01X111663Y-839672D02*
X114323Y-834672D01*
G01X111663D02*
X114323Y-839672D01*
G01X118093Y-839839D02*
X117966Y-839755D01*
Y-839589D01*
X118093Y-839505D01*
X118220Y-839589D01*
Y-839755D01*
X118093Y-839839D01*
G01Y-837589D02*
X117966Y-837505D01*
Y-837339D01*
X118093Y-837255D01*
X118220Y-837339D01*
Y-837505D01*
X118093Y-837589D01*
G01X122876Y-841339D02*
X122243Y-840505D01*
X121926Y-839672D01*
Y-836339D01*
X122243Y-835505D01*
X122876Y-834672D01*
G01X128293D02*
X127786Y-834839D01*
X127406Y-835255D01*
X127153Y-835755D01*
X126963Y-836422D01*
X126900Y-837172D01*
X126963Y-837922D01*
X127153Y-838589D01*
X127406Y-839089D01*
X127786Y-839505D01*
X128293Y-839672D01*
X128800Y-839505D01*
X129180Y-839089D01*
X129433Y-838589D01*
X129623Y-837922D01*
X129686Y-837172D01*
X129623Y-836422D01*
X129433Y-835755D01*
X129180Y-835255D01*
X128800Y-834839D01*
X128293Y-834672D01*
G01X132000Y-838672D02*
X132380Y-839255D01*
X132886Y-839589D01*
X133456Y-839672D01*
X133963Y-839589D01*
X134470Y-839172D01*
X134786Y-838672D01*
X134850Y-838172D01*
X134723Y-837589D01*
X134280Y-837172D01*
X133836Y-837005D01*
X133266D01*
G01X133836D02*
X134216Y-836755D01*
X134533Y-836339D01*
X134660Y-835839D01*
X134533Y-835339D01*
X134216Y-834922D01*
X133646Y-834672D01*
X133076Y-834755D01*
X132506Y-835089D01*
G01X138810Y-841339D02*
X139443Y-840505D01*
X139760Y-839672D01*
Y-836339D01*
X139443Y-835505D01*
X138810Y-834672D01*
G01X142200Y-838672D02*
X142580Y-839255D01*
X143086Y-839589D01*
X143656Y-839672D01*
X144163Y-839589D01*
X144670Y-839172D01*
X144986Y-838672D01*
X145050Y-838172D01*
X144923Y-837589D01*
X144480Y-837172D01*
X144036Y-837005D01*
X143466D01*
G01X144036D02*
X144416Y-836755D01*
X144733Y-836339D01*
X144860Y-835839D01*
X144733Y-835339D01*
X144416Y-834922D01*
X143846Y-834672D01*
X143276Y-834755D01*
X142706Y-835089D01*
G01X147616Y-839089D02*
X148060Y-839505D01*
X148566Y-839672D01*
X149073Y-839505D01*
X149516Y-839005D01*
X149833Y-838255D01*
X149960Y-837505D01*
Y-836589D01*
X149833Y-835839D01*
X149516Y-835172D01*
X149136Y-834839D01*
X148693Y-834672D01*
X148186Y-834839D01*
X147806Y-835172D01*
X147553Y-835672D01*
X147426Y-836339D01*
X147553Y-836922D01*
X147870Y-837505D01*
X148250Y-837839D01*
X148693Y-837922D01*
X149200Y-837755D01*
X149580Y-837339D01*
X149960Y-836589D01*
G01X153666Y-839672D02*
X153793Y-838589D01*
X153983Y-837672D01*
X154236Y-836839D01*
X154553Y-835922D01*
X155060Y-834672D01*
X152526D01*
G01X158070Y-838005D02*
X159716D01*
G01X162600Y-838672D02*
X162980Y-839255D01*
X163486Y-839589D01*
X164056Y-839672D01*
X164563Y-839589D01*
X165070Y-839172D01*
X165386Y-838672D01*
X165450Y-838172D01*
X165323Y-837589D01*
X164880Y-837172D01*
X164436Y-837005D01*
X163866D01*
G01X164436D02*
X164816Y-836755D01*
X165133Y-836339D01*
X165260Y-835839D01*
X165133Y-835339D01*
X164816Y-834922D01*
X164246Y-834672D01*
X163676Y-834755D01*
X163106Y-835089D01*
G01X167890Y-837589D02*
X168333Y-837005D01*
X168713Y-836672D01*
X169220Y-836505D01*
X169663Y-836672D01*
X169980Y-837005D01*
X170233Y-837505D01*
X170296Y-838089D01*
X170233Y-838589D01*
X169980Y-839089D01*
X169600Y-839505D01*
X169156Y-839672D01*
X168650Y-839505D01*
X168206Y-839005D01*
X167953Y-838255D01*
X167890Y-837422D01*
X168016Y-836339D01*
X168206Y-835755D01*
X168523Y-835172D01*
X168966Y-834755D01*
X169410Y-834672D01*
X169853Y-834839D01*
X170170Y-835255D01*
G01X174193Y-839672D02*
Y-834672D01*
X173433Y-835672D01*
G01Y-839672D02*
X174953D01*
G01X180053D02*
Y-834672D01*
X177710Y-838255D01*
X180876D01*
G01X199093Y-769672D02*
Y-844672D01*
G01Y-819672D02*
X302093D01*
Y-794672D01*
G01X199093D02*
X302093D01*
G01X309600Y-829672D02*
Y-824672D01*
X310866D01*
X311373Y-824922D01*
X311753Y-825255D01*
X312070Y-825755D01*
X312323Y-826339D01*
X312386Y-827172D01*
X312323Y-828005D01*
X312070Y-828589D01*
X311753Y-829089D01*
X311373Y-829422D01*
X310866Y-829672D01*
X309600D01*
G01X314510D02*
X316093Y-824672D01*
X317676Y-829672D01*
G01X317106Y-827922D02*
X315080D01*
G01X321193Y-824672D02*
Y-829672D01*
G01X319736Y-824672D02*
X322650D01*
G01X327560Y-829672D02*
X325026D01*
Y-824672D01*
X327560D01*
G01X326546Y-827089D02*
X325026D01*
G01X331393Y-829839D02*
X331266Y-829755D01*
Y-829589D01*
X331393Y-829505D01*
X331520Y-829589D01*
Y-829755D01*
X331393Y-829839D01*
G01Y-827589D02*
X331266Y-827505D01*
Y-827339D01*
X331393Y-827255D01*
X331520Y-827339D01*
Y-827505D01*
X331393Y-827589D01*
G01X304093Y-769672D02*
Y-844672D01*
G01X302093Y-769672D02*
Y-844672D01*
G01X304093Y-819672D02*
X504093D01*
G01X309726Y-804672D02*
Y-799672D01*
X311246D01*
X311753Y-799922D01*
X312133Y-800505D01*
X312260Y-801172D01*
X312133Y-801839D01*
X311816Y-802339D01*
X311246Y-802589D01*
X309726D01*
G01X314953Y-804839D02*
X317233Y-799672D01*
G01X319736Y-804672D02*
Y-799672D01*
X322650Y-804672D01*
Y-799672D01*
G01X326293Y-804839D02*
X326166Y-804755D01*
Y-804589D01*
X326293Y-804505D01*
X326420Y-804589D01*
Y-804755D01*
X326293Y-804839D01*
G01Y-802589D02*
X326166Y-802505D01*
Y-802339D01*
X326293Y-802255D01*
X326420Y-802339D01*
Y-802505D01*
X326293Y-802589D01*
G01X304093Y-794672D02*
X504093D01*
G01X309726Y-779672D02*
Y-774672D01*
X311246D01*
X311753Y-774922D01*
X312133Y-775505D01*
X312260Y-776172D01*
X312133Y-776839D01*
X311816Y-777339D01*
X311246Y-777589D01*
X309726D01*
G01X314826Y-779672D02*
Y-774672D01*
X316410D01*
X316916Y-774922D01*
X317233Y-775255D01*
X317360Y-775922D01*
X317233Y-776589D01*
X316853Y-777005D01*
X316410Y-777255D01*
X314826D01*
G01X316410D02*
X317360Y-779672D01*
G01X321193D02*
X320686Y-779589D01*
X320243Y-779255D01*
X319863Y-778755D01*
X319610Y-778172D01*
X319483Y-777505D01*
Y-776839D01*
X319610Y-776172D01*
X319863Y-775589D01*
X320243Y-775089D01*
X320686Y-774755D01*
X321193Y-774672D01*
X321700Y-774755D01*
X322143Y-775089D01*
X322523Y-775589D01*
X322776Y-776172D01*
X322903Y-776839D01*
Y-777505D01*
X322776Y-778172D01*
X322523Y-778755D01*
X322143Y-779255D01*
X321700Y-779589D01*
X321193Y-779672D01*
G01X325026Y-778672D02*
X325343Y-779172D01*
X325723Y-779505D01*
X326166Y-779672D01*
X326673Y-779505D01*
X327053Y-779172D01*
X327433Y-778672D01*
X327560Y-778005D01*
Y-774672D01*
G01X332660Y-779672D02*
X330126D01*
Y-774672D01*
X332660D01*
G01X331646Y-777089D02*
X330126D01*
G01X337886Y-775089D02*
X337506Y-774839D01*
X337063Y-774672D01*
X336556D01*
X335986Y-774922D01*
X335543Y-775339D01*
X335226Y-775839D01*
X334973Y-776672D01*
X334910Y-777422D01*
X335036Y-778172D01*
X335226Y-778672D01*
X335606Y-779172D01*
X336050Y-779505D01*
X336493Y-779672D01*
X336936D01*
X337380Y-779505D01*
X337760Y-779255D01*
X338076Y-778922D01*
G01X341593Y-774672D02*
Y-779672D01*
G01X340136Y-774672D02*
X343050D01*
G01X346693Y-779839D02*
X346566Y-779755D01*
Y-779589D01*
X346693Y-779505D01*
X346820Y-779589D01*
Y-779755D01*
X346693Y-779839D01*
G01Y-777589D02*
X346566Y-777505D01*
Y-777339D01*
X346693Y-777255D01*
X346820Y-777339D01*
Y-777505D01*
X346693Y-777589D01*
G01X419093Y-819672D02*
Y-844672D01*
G01X421726Y-822172D02*
Y-827172D01*
X424260D01*
G01X427333Y-822172D02*
X428853D01*
G01X428093D02*
Y-827172D01*
G01X427333D02*
X428853D01*
G01X433700Y-824505D02*
X433953Y-824255D01*
X434143Y-823839D01*
X434270Y-823255D01*
X434143Y-822755D01*
X433890Y-822422D01*
X433446Y-822172D01*
X431736D01*
Y-827172D01*
X433826D01*
X434270Y-826839D01*
X434523Y-826339D01*
X434650Y-825755D01*
X434523Y-825172D01*
X434143Y-824672D01*
X433700Y-824505D01*
X431736D01*
G01X438293Y-827339D02*
X438166Y-827255D01*
Y-827089D01*
X438293Y-827005D01*
X438420Y-827089D01*
Y-827255D01*
X438293Y-827339D01*
G01Y-825089D02*
X438166Y-825005D01*
Y-824839D01*
X438293Y-824755D01*
X438420Y-824839D01*
Y-825005D01*
X438293Y-825089D01*
G01X470106Y-847839D02*
X470213Y-847714D01*
X470293Y-847505D01*
X470346Y-847214D01*
X470293Y-846964D01*
X470186Y-846797D01*
X470000Y-846672D01*
X469280D01*
Y-849172D01*
X470160D01*
X470346Y-849005D01*
X470453Y-848755D01*
X470506Y-848464D01*
X470453Y-848172D01*
X470293Y-847922D01*
X470106Y-847839D01*
X469280D01*
G01X472573Y-849172D02*
Y-847505D01*
G01Y-847797D02*
X472466Y-847630D01*
X472306Y-847547D01*
X472120Y-847505D01*
X471933Y-847589D01*
X471773Y-847755D01*
X471666Y-848005D01*
X471613Y-848339D01*
X471666Y-848672D01*
X471773Y-848922D01*
X471933Y-849089D01*
X472120Y-849172D01*
X472306Y-849130D01*
X472466Y-849005D01*
X472573Y-848839D01*
G01X473893Y-848880D02*
X474026Y-849047D01*
X474213Y-849172D01*
X474373D01*
X474533Y-849089D01*
X474640Y-848964D01*
X474693Y-848797D01*
X474666Y-848547D01*
X474560Y-848422D01*
X474080Y-848172D01*
X473973Y-847880D01*
X474026Y-847672D01*
X474133Y-847547D01*
X474293Y-847505D01*
X474453Y-847547D01*
X474613Y-847672D01*
G01X476093Y-848047D02*
X476946D01*
X476866Y-847755D01*
X476733Y-847589D01*
X476546Y-847505D01*
X476360Y-847547D01*
X476200Y-847672D01*
X476093Y-847964D01*
X476040Y-848214D01*
Y-848464D01*
X476093Y-848714D01*
X476226Y-848964D01*
X476386Y-849130D01*
X476573Y-849172D01*
X476760Y-849089D01*
X476946Y-848839D01*
G01X478213Y-849172D02*
Y-846672D01*
G01Y-847922D02*
X478346Y-847672D01*
X478506Y-847547D01*
X478666Y-847505D01*
X478906Y-847589D01*
X479066Y-847755D01*
X479173Y-848047D01*
Y-848380D01*
X479120Y-848714D01*
X479013Y-848964D01*
X478826Y-849130D01*
X478666Y-849172D01*
X478506Y-849130D01*
X478346Y-849005D01*
X478213Y-848797D01*
G01X480893Y-849172D02*
X480733Y-849130D01*
X480573Y-848964D01*
X480466Y-848672D01*
X480413Y-848339D01*
X480466Y-848005D01*
X480573Y-847714D01*
X480733Y-847547D01*
X480893Y-847505D01*
X481053Y-847547D01*
X481213Y-847714D01*
X481320Y-848005D01*
X481346Y-848339D01*
X481320Y-848672D01*
X481213Y-848964D01*
X481053Y-849130D01*
X480893Y-849172D01*
G01X483573D02*
Y-847505D01*
G01Y-847797D02*
X483466Y-847630D01*
X483306Y-847547D01*
X483120Y-847505D01*
X482933Y-847589D01*
X482773Y-847755D01*
X482666Y-848005D01*
X482613Y-848339D01*
X482666Y-848672D01*
X482773Y-848922D01*
X482933Y-849089D01*
X483120Y-849172D01*
X483306Y-849130D01*
X483466Y-849005D01*
X483573Y-848839D01*
G01X484920Y-849172D02*
Y-847505D01*
G01Y-847839D02*
X485053Y-847672D01*
X485186Y-847547D01*
X485373Y-847505D01*
X485506Y-847547D01*
X485666Y-847672D01*
G01X487973Y-846672D02*
Y-849172D01*
G01Y-848797D02*
X487866Y-849005D01*
X487706Y-849130D01*
X487520Y-849172D01*
X487306Y-849089D01*
X487146Y-848880D01*
X487040Y-848630D01*
X487013Y-848339D01*
X487040Y-848047D01*
X487146Y-847797D01*
X487306Y-847589D01*
X487520Y-847505D01*
X487706Y-847547D01*
X487840Y-847630D01*
X487973Y-847797D01*
G01X491360Y-849172D02*
Y-846672D01*
X492026D01*
X492240Y-846797D01*
X492373Y-846964D01*
X492426Y-847297D01*
X492373Y-847630D01*
X492213Y-847839D01*
X492026Y-847964D01*
X491360D01*
G01X492026D02*
X492426Y-849172D01*
G01X493693Y-848047D02*
X494546D01*
X494466Y-847755D01*
X494333Y-847589D01*
X494146Y-847505D01*
X493960Y-847547D01*
X493800Y-847672D01*
X493693Y-847964D01*
X493640Y-848214D01*
Y-848464D01*
X493693Y-848714D01*
X493826Y-848964D01*
X493986Y-849130D01*
X494173Y-849172D01*
X494360Y-849089D01*
X494546Y-848839D01*
G01X495813Y-847505D02*
X496293Y-849172D01*
X496773Y-847505D01*
G01X498493Y-849255D02*
X498440Y-849214D01*
Y-849130D01*
X498493Y-849089D01*
X498546Y-849130D01*
Y-849214D01*
X498493Y-849255D01*
G01X500693Y-849172D02*
X500880Y-849130D01*
X501093Y-849005D01*
X501226Y-848797D01*
X501280Y-848505D01*
X501226Y-848214D01*
X501066Y-847964D01*
X500826Y-847839D01*
X500560D01*
X500400Y-847755D01*
X500266Y-847547D01*
X500213Y-847255D01*
X500293Y-846964D01*
X500480Y-846755D01*
X500693Y-846672D01*
X500906Y-846755D01*
X501093Y-846964D01*
X501173Y-847255D01*
X501120Y-847547D01*
X500986Y-847755D01*
X500826Y-847839D01*
X500560D01*
X500320Y-847964D01*
X500160Y-848214D01*
X500106Y-848505D01*
X500160Y-848797D01*
X500293Y-849005D01*
X500506Y-849130D01*
X500693Y-849172D01*
G01X503106Y-847839D02*
X503213Y-847714D01*
X503293Y-847505D01*
X503346Y-847214D01*
X503293Y-846964D01*
X503186Y-846797D01*
X503000Y-846672D01*
X502280D01*
Y-849172D01*
X503160D01*
X503346Y-849005D01*
X503453Y-848755D01*
X503506Y-848464D01*
X503453Y-848172D01*
X503293Y-847922D01*
X503106Y-847839D01*
X502280D01*
G01X465993Y-822172D02*
Y-827172D01*
G01X464536Y-822172D02*
X467450D01*
G01X471093Y-827172D02*
X470713Y-827089D01*
X470333Y-826755D01*
X470080Y-826172D01*
X469953Y-825505D01*
X470080Y-824839D01*
X470333Y-824255D01*
X470713Y-823922D01*
X471093Y-823839D01*
X471473Y-823922D01*
X471853Y-824255D01*
X472106Y-824839D01*
X472170Y-825505D01*
X472106Y-826172D01*
X471853Y-826755D01*
X471473Y-827089D01*
X471093Y-827172D01*
G01X476193D02*
X475813Y-827089D01*
X475433Y-826755D01*
X475180Y-826172D01*
X475053Y-825505D01*
X475180Y-824839D01*
X475433Y-824255D01*
X475813Y-823922D01*
X476193Y-823839D01*
X476573Y-823922D01*
X476953Y-824255D01*
X477206Y-824839D01*
X477270Y-825505D01*
X477206Y-826172D01*
X476953Y-826755D01*
X476573Y-827089D01*
X476193Y-827172D01*
G01X481293D02*
Y-822172D01*
G01X486393Y-827339D02*
X486266Y-827255D01*
Y-827089D01*
X486393Y-827005D01*
X486520Y-827089D01*
Y-827255D01*
X486393Y-827339D01*
G01Y-825089D02*
X486266Y-825005D01*
Y-824839D01*
X486393Y-824755D01*
X486520Y-824839D01*
Y-825005D01*
X486393Y-825089D01*
G01X462093Y-819672D02*
Y-844672D01*
G01Y-794672D02*
Y-819672D01*
G01X464726Y-802172D02*
Y-797172D01*
X466310D01*
X466816Y-797422D01*
X467133Y-797755D01*
X467260Y-798422D01*
X467133Y-799089D01*
X466753Y-799505D01*
X466310Y-799755D01*
X464726D01*
G01X466310D02*
X467260Y-802172D01*
G01X472360D02*
X469826D01*
Y-797172D01*
X472360D01*
G01X471346Y-799589D02*
X469826D01*
G01X474610Y-797172D02*
X476193Y-802172D01*
X477776Y-797172D01*
G01X481293Y-802339D02*
X481166Y-802255D01*
Y-802089D01*
X481293Y-802005D01*
X481420Y-802089D01*
Y-802255D01*
X481293Y-802339D01*
G01Y-800089D02*
X481166Y-800005D01*
Y-799839D01*
X481293Y-799755D01*
X481420Y-799839D01*
Y-800005D01*
X481293Y-800089D01*
G01X-297025Y-1013390D02*
Y1828909D01*
X3691357D01*
Y-1013390D01*
X-297025D01*
G01X16913Y-817022D02*
X18480D01*
Y-818912D01*
X18010Y-819542D01*
X17461Y-819962D01*
X16678Y-820172D01*
X15895Y-819962D01*
X15346Y-819542D01*
X14876Y-818912D01*
X14563Y-818177D01*
X14406Y-817337D01*
Y-816602D01*
X14563Y-815972D01*
X14876Y-815237D01*
X15346Y-814607D01*
X15816Y-814187D01*
X16443Y-813872D01*
X16991D01*
X17618Y-814082D01*
X18088Y-814502D01*
G01X21020Y-813872D02*
Y-818387D01*
X21333Y-819332D01*
X21960Y-819962D01*
X22743Y-820172D01*
X23526Y-819962D01*
X24153Y-819332D01*
X24466Y-818387D01*
Y-813872D01*
G01X28103D02*
X29983D01*
G01X29043D02*
Y-820172D01*
G01X28103D02*
X29983D01*
G01X33698Y-819332D02*
X34325Y-819857D01*
X35030Y-820172D01*
X35656D01*
X36283Y-819857D01*
X36753Y-819332D01*
X36988Y-818597D01*
X36831Y-817862D01*
X36440Y-817232D01*
X35735Y-816812D01*
X34795Y-816602D01*
X34246Y-816182D01*
X34011Y-815447D01*
X34168Y-814712D01*
X34560Y-814187D01*
X35108Y-813872D01*
X35656D01*
X36205Y-814082D01*
X36675Y-814607D01*
G01X39998Y-820172D02*
Y-813872D01*
G01X43288D02*
Y-820172D01*
G01Y-817022D02*
X39998D01*
G01X45985Y-820172D02*
X47943Y-813872D01*
X49901Y-820172D01*
G01X49196Y-817967D02*
X46690D01*
G01X52441Y-820172D02*
Y-813872D01*
X56045Y-820172D01*
Y-813872D01*
G01X65120Y-820172D02*
Y-813872D01*
X66686D01*
X67313Y-814187D01*
X67783Y-814607D01*
X68175Y-815237D01*
X68488Y-815972D01*
X68566Y-817022D01*
X68488Y-818072D01*
X68175Y-818807D01*
X67783Y-819437D01*
X67313Y-819857D01*
X66686Y-820172D01*
X65120D01*
G01X72203Y-813872D02*
X74083D01*
G01X73143D02*
Y-820172D01*
G01X72203D02*
X74083D01*
G01X77798Y-819332D02*
X78425Y-819857D01*
X79130Y-820172D01*
X79756D01*
X80383Y-819857D01*
X80853Y-819332D01*
X81088Y-818597D01*
X80931Y-817862D01*
X80540Y-817232D01*
X79835Y-816812D01*
X78895Y-816602D01*
X78346Y-816182D01*
X78111Y-815447D01*
X78268Y-814712D01*
X78660Y-814187D01*
X79208Y-813872D01*
X79756D01*
X80305Y-814082D01*
X80775Y-814607D01*
G01X85743Y-813872D02*
Y-820172D01*
G01X83941Y-813872D02*
X87545D01*
G01X92043Y-820382D02*
X91886Y-820277D01*
Y-820067D01*
X92043Y-819962D01*
X92200Y-820067D01*
Y-820277D01*
X92043Y-820382D01*
G01X98186Y-821327D02*
X98500Y-819962D01*
G01X104643Y-813872D02*
Y-820172D01*
G01X102841Y-813872D02*
X106445D01*
G01X108985Y-820172D02*
X110943Y-813872D01*
X112901Y-820172D01*
G01X112196Y-817967D02*
X109690D01*
G01X117243Y-820172D02*
X116616Y-820067D01*
X116068Y-819647D01*
X115598Y-819017D01*
X115285Y-818282D01*
X115128Y-817442D01*
Y-816602D01*
X115285Y-815762D01*
X115598Y-815027D01*
X116068Y-814397D01*
X116616Y-813977D01*
X117243Y-813872D01*
X117870Y-813977D01*
X118418Y-814397D01*
X118888Y-815027D01*
X119201Y-815762D01*
X119358Y-816602D01*
Y-817442D01*
X119201Y-818282D01*
X118888Y-819017D01*
X118418Y-819647D01*
X117870Y-820067D01*
X117243Y-820172D01*
G01X123543D02*
Y-817337D01*
X121976Y-813872D01*
G01X125110D02*
X123543Y-817337D01*
G01X128120Y-813872D02*
Y-818387D01*
X128433Y-819332D01*
X129060Y-819962D01*
X129843Y-820172D01*
X130626Y-819962D01*
X131253Y-819332D01*
X131566Y-818387D01*
Y-813872D01*
G01X134185Y-820172D02*
X136143Y-813872D01*
X138101Y-820172D01*
G01X137396Y-817967D02*
X134890D01*
G01X140641Y-820172D02*
Y-813872D01*
X144245Y-820172D01*
Y-813872D01*
G01X18166Y-824397D02*
X17696Y-824082D01*
X17148Y-823872D01*
X16521D01*
X15816Y-824187D01*
X15268Y-824712D01*
X14876Y-825342D01*
X14563Y-826392D01*
X14485Y-827337D01*
X14641Y-828282D01*
X14876Y-828912D01*
X15346Y-829542D01*
X15895Y-829962D01*
X16443Y-830172D01*
X16991D01*
X17540Y-829962D01*
X18010Y-829647D01*
X18401Y-829227D01*
G01X21803Y-823872D02*
X23683D01*
G01X22743D02*
Y-830172D01*
G01X21803D02*
X23683D01*
G01X29043Y-823872D02*
Y-830172D01*
G01X27241Y-823872D02*
X30845D01*
G01X35343Y-830172D02*
Y-827337D01*
X33776Y-823872D01*
G01X36910D02*
X35343Y-827337D01*
G01X46220Y-828912D02*
X46690Y-829647D01*
X47316Y-830067D01*
X48021Y-830172D01*
X48648Y-830067D01*
X49275Y-829542D01*
X49666Y-828912D01*
X49745Y-828282D01*
X49588Y-827547D01*
X49040Y-827022D01*
X48491Y-826812D01*
X47786D01*
G01X48491D02*
X48961Y-826497D01*
X49353Y-825972D01*
X49510Y-825342D01*
X49353Y-824712D01*
X48961Y-824187D01*
X48256Y-823872D01*
X47551Y-823977D01*
X46846Y-824397D01*
G01X52520Y-828912D02*
X52990Y-829647D01*
X53616Y-830067D01*
X54321Y-830172D01*
X54948Y-830067D01*
X55575Y-829542D01*
X55966Y-828912D01*
X56045Y-828282D01*
X55888Y-827547D01*
X55340Y-827022D01*
X54791Y-826812D01*
X54086D01*
G01X54791D02*
X55261Y-826497D01*
X55653Y-825972D01*
X55810Y-825342D01*
X55653Y-824712D01*
X55261Y-824187D01*
X54556Y-823872D01*
X53851Y-823977D01*
X53146Y-824397D01*
G01X58820Y-828912D02*
X59290Y-829647D01*
X59916Y-830067D01*
X60621Y-830172D01*
X61248Y-830067D01*
X61875Y-829542D01*
X62266Y-828912D01*
X62345Y-828282D01*
X62188Y-827547D01*
X61640Y-827022D01*
X61091Y-826812D01*
X60386D01*
G01X61091D02*
X61561Y-826497D01*
X61953Y-825972D01*
X62110Y-825342D01*
X61953Y-824712D01*
X61561Y-824187D01*
X60856Y-823872D01*
X60151Y-823977D01*
X59446Y-824397D01*
G01X66686Y-830172D02*
X66843Y-828807D01*
X67078Y-827652D01*
X67391Y-826602D01*
X67783Y-825447D01*
X68410Y-823872D01*
X65276D01*
G01X72986Y-830172D02*
X73143Y-828807D01*
X73378Y-827652D01*
X73691Y-826602D01*
X74083Y-825447D01*
X74710Y-823872D01*
X71576D01*
G01X79286Y-831327D02*
X79600Y-829962D01*
G01X85743Y-823872D02*
Y-830172D01*
G01X83941Y-823872D02*
X87545D01*
G01X90085Y-830172D02*
X92043Y-823872D01*
X94001Y-830172D01*
G01X93296Y-827967D02*
X90790D01*
G01X97403Y-823872D02*
X99283D01*
G01X98343D02*
Y-830172D01*
G01X97403D02*
X99283D01*
G01X102293Y-823872D02*
X103390Y-830172D01*
X104643Y-823872D01*
X105896Y-830172D01*
X106993Y-823872D01*
G01X108985Y-830172D02*
X110943Y-823872D01*
X112901Y-830172D01*
G01X112196Y-827967D02*
X109690D01*
G01X115441Y-830172D02*
Y-823872D01*
X119045Y-830172D01*
Y-823872D01*
G01X129451Y-832272D02*
X128668Y-831222D01*
X128276Y-830172D01*
Y-825972D01*
X128668Y-824922D01*
X129451Y-823872D01*
G01X140876Y-830172D02*
Y-823872D01*
X142835D01*
X143461Y-824187D01*
X143853Y-824607D01*
X144010Y-825447D01*
X143853Y-826287D01*
X143383Y-826812D01*
X142835Y-827127D01*
X140876D01*
G01X142835D02*
X144010Y-830172D01*
G01X148743Y-830382D02*
X148586Y-830277D01*
Y-830067D01*
X148743Y-829962D01*
X148900Y-830067D01*
Y-830277D01*
X148743Y-830382D01*
G01X155043Y-830172D02*
X154416Y-830067D01*
X153868Y-829647D01*
X153398Y-829017D01*
X153085Y-828282D01*
X152928Y-827442D01*
Y-826602D01*
X153085Y-825762D01*
X153398Y-825027D01*
X153868Y-824397D01*
X154416Y-823977D01*
X155043Y-823872D01*
X155670Y-823977D01*
X156218Y-824397D01*
X156688Y-825027D01*
X157001Y-825762D01*
X157158Y-826602D01*
Y-827442D01*
X157001Y-828282D01*
X156688Y-829017D01*
X156218Y-829647D01*
X155670Y-830067D01*
X155043Y-830172D01*
G01X161343Y-830382D02*
X161186Y-830277D01*
Y-830067D01*
X161343Y-829962D01*
X161500Y-830067D01*
Y-830277D01*
X161343Y-830382D01*
G01X169366Y-824397D02*
X168896Y-824082D01*
X168348Y-823872D01*
X167721D01*
X167016Y-824187D01*
X166468Y-824712D01*
X166076Y-825342D01*
X165763Y-826392D01*
X165685Y-827337D01*
X165841Y-828282D01*
X166076Y-828912D01*
X166546Y-829542D01*
X167095Y-829962D01*
X167643Y-830172D01*
X168191D01*
X168740Y-829962D01*
X169210Y-829647D01*
X169601Y-829227D01*
G01X173943Y-830382D02*
X173786Y-830277D01*
Y-830067D01*
X173943Y-829962D01*
X174100Y-830067D01*
Y-830277D01*
X173943Y-830382D01*
G01X180635Y-832272D02*
X181418Y-831222D01*
X181810Y-830172D01*
Y-825972D01*
X181418Y-824922D01*
X180635Y-823872D01*
G01X38743Y-799472D02*
X36223Y-799055D01*
X34018Y-797389D01*
X32128Y-794889D01*
X30868Y-791972D01*
X30238Y-788639D01*
Y-785305D01*
X30868Y-781972D01*
X32128Y-779055D01*
X34018Y-776556D01*
X36223Y-774889D01*
X38743Y-774472D01*
X41263Y-774889D01*
X43468Y-776556D01*
X45358Y-779055D01*
X46618Y-781972D01*
X47248Y-785305D01*
Y-788639D01*
X46618Y-791972D01*
X45358Y-794889D01*
X43468Y-797389D01*
X41263Y-799055D01*
X38743Y-799472D01*
G01X41263Y-792805D02*
X45043Y-799472D01*
G01X58588Y-782806D02*
Y-794472D01*
X59848Y-797389D01*
X61738Y-799055D01*
X63943Y-799472D01*
X66148Y-799055D01*
X68038Y-797389D01*
X69298Y-794472D01*
G01Y-799472D02*
Y-782806D01*
G01X94813Y-799472D02*
Y-782806D01*
G01Y-785722D02*
X93553Y-784056D01*
X91663Y-783222D01*
X89458Y-782806D01*
X87253Y-783639D01*
X85363Y-785305D01*
X84103Y-787806D01*
X83473Y-791139D01*
X84103Y-794472D01*
X85363Y-796973D01*
X87253Y-798639D01*
X89458Y-799472D01*
X91663Y-799055D01*
X93553Y-797806D01*
X94813Y-796139D01*
G01X108988Y-799472D02*
Y-782806D01*
G01Y-786972D02*
X110248Y-784889D01*
X112138Y-783222D01*
X114658Y-782806D01*
X116863Y-783222D01*
X118753Y-784889D01*
X119698Y-787806D01*
Y-799472D01*
G01X139543Y-774472D02*
Y-799472D01*
G01X135133Y-782806D02*
X143953D01*
G01X170413Y-799472D02*
Y-782806D01*
G01Y-785722D02*
X169153Y-784056D01*
X167263Y-783222D01*
X165058Y-782806D01*
X162853Y-783639D01*
X160963Y-785305D01*
X159703Y-787806D01*
X159073Y-791139D01*
X159703Y-794472D01*
X160963Y-796973D01*
X162853Y-798639D01*
X165058Y-799472D01*
X167263Y-799055D01*
X169153Y-797806D01*
X170413Y-796139D01*
G01X14641Y-810172D02*
Y-803872D01*
X18245Y-810172D01*
Y-803872D01*
G01X22743Y-810172D02*
X22116Y-810067D01*
X21568Y-809647D01*
X21098Y-809017D01*
X20785Y-808282D01*
X20628Y-807442D01*
Y-806602D01*
X20785Y-805762D01*
X21098Y-805027D01*
X21568Y-804397D01*
X22116Y-803977D01*
X22743Y-803872D01*
X23370Y-803977D01*
X23918Y-804397D01*
X24388Y-805027D01*
X24701Y-805762D01*
X24858Y-806602D01*
Y-807442D01*
X24701Y-808282D01*
X24388Y-809017D01*
X23918Y-809647D01*
X23370Y-810067D01*
X22743Y-810172D01*
G01X29043Y-810382D02*
X28886Y-810277D01*
Y-810067D01*
X29043Y-809962D01*
X29200Y-810067D01*
Y-810277D01*
X29043Y-810382D01*
G01X33855Y-804922D02*
X34325Y-804292D01*
X34873Y-803977D01*
X35500Y-803872D01*
X36283Y-804082D01*
X36831Y-804607D01*
X36988Y-805237D01*
X36910Y-805867D01*
X36596Y-806392D01*
X35030Y-807442D01*
X34325Y-808177D01*
X33855Y-809227D01*
X33698Y-810172D01*
X36988D01*
G01X41643D02*
Y-803872D01*
X40703Y-805132D01*
G01Y-810172D02*
X42583D01*
G01X47943D02*
Y-803872D01*
X47003Y-805132D01*
G01Y-810172D02*
X48883D01*
G01X54086Y-811327D02*
X54400Y-809962D01*
G01X58193Y-803872D02*
X59290Y-810172D01*
X60543Y-803872D01*
X61796Y-810172D01*
X62893Y-803872D01*
G01X68410Y-810172D02*
X65276D01*
Y-803872D01*
X68410D01*
G01X67156Y-806917D02*
X65276D01*
G01X71341Y-810172D02*
Y-803872D01*
X74945Y-810172D01*
Y-803872D01*
G01X77798Y-810172D02*
Y-803872D01*
G01X81088D02*
Y-810172D01*
G01Y-807022D02*
X77798D01*
G01X84020Y-803872D02*
Y-808387D01*
X84333Y-809332D01*
X84960Y-809962D01*
X85743Y-810172D01*
X86526Y-809962D01*
X87153Y-809332D01*
X87466Y-808387D01*
Y-803872D01*
G01X90085Y-810172D02*
X92043Y-803872D01*
X94001Y-810172D01*
G01X93296Y-807967D02*
X90790D01*
G01X103155Y-804922D02*
X103625Y-804292D01*
X104173Y-803977D01*
X104800Y-803872D01*
X105583Y-804082D01*
X106131Y-804607D01*
X106288Y-805237D01*
X106210Y-805867D01*
X105896Y-806392D01*
X104330Y-807442D01*
X103625Y-808177D01*
X103155Y-809227D01*
X102998Y-810172D01*
X106288D01*
G01X109141D02*
Y-803872D01*
X112745Y-810172D01*
Y-803872D01*
G01X115520Y-810172D02*
Y-803872D01*
X117086D01*
X117713Y-804187D01*
X118183Y-804607D01*
X118575Y-805237D01*
X118888Y-805972D01*
X118966Y-807022D01*
X118888Y-808072D01*
X118575Y-808807D01*
X118183Y-809437D01*
X117713Y-809857D01*
X117086Y-810172D01*
X115520D01*
G01X128276D02*
Y-803872D01*
X130235D01*
X130861Y-804187D01*
X131253Y-804607D01*
X131410Y-805447D01*
X131253Y-806287D01*
X130783Y-806812D01*
X130235Y-807127D01*
X128276D01*
G01X130235D02*
X131410Y-810172D01*
G01X134420D02*
Y-803872D01*
X135986D01*
X136613Y-804187D01*
X137083Y-804607D01*
X137475Y-805237D01*
X137788Y-805972D01*
X137866Y-807022D01*
X137788Y-808072D01*
X137475Y-808807D01*
X137083Y-809437D01*
X136613Y-809857D01*
X135986Y-810172D01*
X134420D01*
G01X142443Y-810382D02*
X142286Y-810277D01*
Y-810067D01*
X142443Y-809962D01*
X142600Y-810067D01*
Y-810277D01*
X142443Y-810382D01*
G01X210093Y-779172D02*
Y-787172D01*
X214093D01*
G01X221893D02*
Y-781839D01*
G01Y-782772D02*
X221493Y-782239D01*
X220893Y-781972D01*
X220193Y-781839D01*
X219493Y-782105D01*
X218893Y-782639D01*
X218493Y-783439D01*
X218293Y-784505D01*
X218493Y-785572D01*
X218893Y-786372D01*
X219493Y-786905D01*
X220193Y-787172D01*
X220893Y-787039D01*
X221493Y-786639D01*
X221893Y-786106D01*
G01X225993Y-789572D02*
X226593Y-789839D01*
X227393Y-789572D01*
X227893Y-789039D01*
X228293Y-788372D01*
X228893Y-786239D01*
X230193Y-781839D01*
G01X226993D02*
X228893Y-786239D01*
G01X234593Y-783572D02*
X237793D01*
X237493Y-782639D01*
X236993Y-782105D01*
X236293Y-781839D01*
X235593Y-781972D01*
X234993Y-782372D01*
X234593Y-783305D01*
X234393Y-784106D01*
Y-784905D01*
X234593Y-785705D01*
X235093Y-786505D01*
X235693Y-787039D01*
X236393Y-787172D01*
X237093Y-786905D01*
X237793Y-786106D01*
G01X242693Y-787172D02*
Y-781839D01*
G01Y-782905D02*
X243193Y-782372D01*
X243693Y-781972D01*
X244393Y-781839D01*
X244893Y-781972D01*
X245493Y-782372D01*
G01X229193Y-829172D02*
X232993D01*
X229193Y-837172D01*
X232993D01*
G01X239093Y-831839D02*
Y-837172D01*
G01Y-829705D02*
X238893Y-829572D01*
Y-829305D01*
X239093Y-829172D01*
X239293Y-829305D01*
Y-829572D01*
X239093Y-829705D01*
G01X245793Y-834505D02*
X248393D01*
G01X253093Y-837172D02*
Y-829172D01*
X255493D01*
X256293Y-829572D01*
X256893Y-830505D01*
X257093Y-831572D01*
X256893Y-832639D01*
X256393Y-833439D01*
X255493Y-833839D01*
X253093D01*
G01X263093Y-831839D02*
Y-837172D01*
G01Y-829705D02*
X262893Y-829572D01*
Y-829305D01*
X263093Y-829172D01*
X263293Y-829305D01*
Y-829572D01*
X263093Y-829705D01*
G01X269393Y-837172D02*
Y-831839D01*
G01Y-833172D02*
X269793Y-832505D01*
X270393Y-831972D01*
X271193Y-831839D01*
X271893Y-831972D01*
X272493Y-832505D01*
X272793Y-833439D01*
Y-837172D01*
G01X277693Y-839172D02*
X278393Y-839705D01*
X279193Y-839839D01*
X279893Y-839705D01*
X280493Y-839039D01*
X280893Y-838105D01*
Y-831839D01*
G01Y-832905D02*
X280493Y-832372D01*
X279893Y-831972D01*
X279193Y-831839D01*
X278393Y-832105D01*
X277893Y-832639D01*
X277493Y-833572D01*
X277293Y-834505D01*
X277393Y-835305D01*
X277793Y-836239D01*
X278393Y-836905D01*
X279193Y-837172D01*
X279793Y-837039D01*
X280493Y-836505D01*
X280893Y-835972D01*
G01X234393Y-807905D02*
X234793Y-807505D01*
X235093Y-806839D01*
X235293Y-805905D01*
X235093Y-805105D01*
X234693Y-804572D01*
X233993Y-804172D01*
X231293D01*
Y-812172D01*
X234593D01*
X235293Y-811639D01*
X235693Y-810839D01*
X235893Y-809905D01*
X235693Y-808972D01*
X235093Y-808172D01*
X234393Y-807905D01*
X231293D01*
G01X241593Y-812172D02*
X240793Y-812039D01*
X240093Y-811505D01*
X239493Y-810705D01*
X239093Y-809772D01*
X238893Y-808705D01*
Y-807639D01*
X239093Y-806572D01*
X239493Y-805639D01*
X240093Y-804839D01*
X240793Y-804305D01*
X241593Y-804172D01*
X242393Y-804305D01*
X243093Y-804839D01*
X243693Y-805639D01*
X244093Y-806572D01*
X244293Y-807639D01*
Y-808705D01*
X244093Y-809772D01*
X243693Y-810705D01*
X243093Y-811505D01*
X242393Y-812039D01*
X241593Y-812172D01*
G01X249593Y-804172D02*
Y-812172D01*
G01X247293Y-804172D02*
X251893D01*
G01X257593D02*
Y-812172D01*
G01X255293Y-804172D02*
X259893D01*
G01X265593Y-812172D02*
X264793Y-812039D01*
X264093Y-811505D01*
X263493Y-810705D01*
X263093Y-809772D01*
X262893Y-808705D01*
Y-807639D01*
X263093Y-806572D01*
X263493Y-805639D01*
X264093Y-804839D01*
X264793Y-804305D01*
X265593Y-804172D01*
X266393Y-804305D01*
X267093Y-804839D01*
X267693Y-805639D01*
X268093Y-806572D01*
X268293Y-807639D01*
Y-808705D01*
X268093Y-809772D01*
X267693Y-810705D01*
X267093Y-811505D01*
X266393Y-812039D01*
X265593Y-812172D01*
G01X270993D02*
Y-804172D01*
X273593Y-810839D01*
X276193Y-804172D01*
Y-812172D01*
G01X258593Y-787172D02*
Y-779172D01*
X257393Y-780772D01*
G01Y-787172D02*
X259793D01*
G01X266593Y-779172D02*
X265793Y-779439D01*
X265193Y-780105D01*
X264793Y-780905D01*
X264493Y-781972D01*
X264393Y-783172D01*
X264493Y-784372D01*
X264793Y-785439D01*
X265193Y-786239D01*
X265793Y-786905D01*
X266593Y-787172D01*
X267393Y-786905D01*
X267993Y-786239D01*
X268393Y-785439D01*
X268693Y-784372D01*
X268793Y-783172D01*
X268693Y-781972D01*
X268393Y-780905D01*
X267993Y-780105D01*
X267393Y-779439D01*
X266593Y-779172D01*
G01X336693Y-830505D02*
X337293Y-829705D01*
X337993Y-829305D01*
X338793Y-829172D01*
X339793Y-829439D01*
X340493Y-830105D01*
X340693Y-830905D01*
X340593Y-831706D01*
X340193Y-832372D01*
X338193Y-833705D01*
X337293Y-834639D01*
X336693Y-835972D01*
X336493Y-837172D01*
X340693D01*
G01X346593Y-829172D02*
X345793Y-829439D01*
X345193Y-830105D01*
X344793Y-830905D01*
X344493Y-831972D01*
X344393Y-833172D01*
X344493Y-834372D01*
X344793Y-835439D01*
X345193Y-836239D01*
X345793Y-836905D01*
X346593Y-837172D01*
X347393Y-836905D01*
X347993Y-836239D01*
X348393Y-835439D01*
X348693Y-834372D01*
X348793Y-833172D01*
X348693Y-831972D01*
X348393Y-830905D01*
X347993Y-830105D01*
X347393Y-829439D01*
X346593Y-829172D01*
G01X352693Y-830505D02*
X353293Y-829705D01*
X353993Y-829305D01*
X354793Y-829172D01*
X355793Y-829439D01*
X356493Y-830105D01*
X356693Y-830905D01*
X356593Y-831706D01*
X356193Y-832372D01*
X354193Y-833705D01*
X353293Y-834639D01*
X352693Y-835972D01*
X352493Y-837172D01*
X356693D01*
G01X360693Y-830505D02*
X361293Y-829705D01*
X361993Y-829305D01*
X362793Y-829172D01*
X363793Y-829439D01*
X364493Y-830105D01*
X364693Y-830905D01*
X364593Y-831706D01*
X364193Y-832372D01*
X362193Y-833705D01*
X361293Y-834639D01*
X360693Y-835972D01*
X360493Y-837172D01*
X364693D01*
G01X368793Y-837439D02*
X372393Y-829172D01*
G01X378593Y-837172D02*
Y-829172D01*
X377393Y-830772D01*
G01Y-837172D02*
X379793D01*
G01X384693Y-830505D02*
X385293Y-829705D01*
X385993Y-829305D01*
X386793Y-829172D01*
X387793Y-829439D01*
X388493Y-830105D01*
X388693Y-830905D01*
X388593Y-831706D01*
X388193Y-832372D01*
X386193Y-833705D01*
X385293Y-834639D01*
X384693Y-835972D01*
X384493Y-837172D01*
X388693D01*
G01X392793Y-837439D02*
X396393Y-829172D01*
G01X402593D02*
X401793Y-829439D01*
X401193Y-830105D01*
X400793Y-830905D01*
X400493Y-831972D01*
X400393Y-833172D01*
X400493Y-834372D01*
X400793Y-835439D01*
X401193Y-836239D01*
X401793Y-836905D01*
X402593Y-837172D01*
X403393Y-836905D01*
X403993Y-836239D01*
X404393Y-835439D01*
X404693Y-834372D01*
X404793Y-833172D01*
X404693Y-831972D01*
X404393Y-830905D01*
X403993Y-830105D01*
X403393Y-829439D01*
X402593Y-829172D01*
G01X408693Y-830505D02*
X409293Y-829705D01*
X409993Y-829305D01*
X410793Y-829172D01*
X411793Y-829439D01*
X412493Y-830105D01*
X412693Y-830905D01*
X412593Y-831706D01*
X412193Y-832372D01*
X410193Y-833705D01*
X409293Y-834639D01*
X408693Y-835972D01*
X408493Y-837172D01*
X412693D01*
G01X336393Y-814672D02*
Y-806672D01*
X338393D01*
X339193Y-807072D01*
X339793Y-807605D01*
X340293Y-808405D01*
X340693Y-809339D01*
X340793Y-810672D01*
X340693Y-812005D01*
X340293Y-812939D01*
X339793Y-813739D01*
X339193Y-814272D01*
X338393Y-814672D01*
X336393D01*
G01X344093D02*
X346593Y-806672D01*
X349093Y-814672D01*
G01X348193Y-811872D02*
X344993D01*
G01X354593Y-806672D02*
X353793Y-806939D01*
X353193Y-807605D01*
X352793Y-808405D01*
X352493Y-809472D01*
X352393Y-810672D01*
X352493Y-811872D01*
X352793Y-812939D01*
X353193Y-813739D01*
X353793Y-814405D01*
X354593Y-814672D01*
X355393Y-814405D01*
X355993Y-813739D01*
X356393Y-812939D01*
X356693Y-811872D01*
X356793Y-810672D01*
X356693Y-809472D01*
X356393Y-808405D01*
X355993Y-807605D01*
X355393Y-806939D01*
X354593Y-806672D01*
G01X360693Y-814672D02*
Y-806672D01*
X364493D01*
G01X363093Y-810539D02*
X360693D01*
G01X370593Y-806672D02*
X369793Y-806939D01*
X369193Y-807605D01*
X368793Y-808405D01*
X368493Y-809472D01*
X368393Y-810672D01*
X368493Y-811872D01*
X368793Y-812939D01*
X369193Y-813739D01*
X369793Y-814405D01*
X370593Y-814672D01*
X371393Y-814405D01*
X371993Y-813739D01*
X372393Y-812939D01*
X372693Y-811872D01*
X372793Y-810672D01*
X372693Y-809472D01*
X372393Y-808405D01*
X371993Y-807605D01*
X371393Y-806939D01*
X370593Y-806672D01*
G01X378593D02*
Y-814672D01*
G01X376293Y-806672D02*
X380893D01*
G01X384593Y-814672D02*
Y-806672D01*
X386993D01*
X387793Y-807072D01*
X388393Y-808005D01*
X388593Y-809072D01*
X388393Y-810139D01*
X387893Y-810939D01*
X386993Y-811339D01*
X384593D01*
G01X395393Y-810405D02*
X395793Y-810005D01*
X396093Y-809339D01*
X396293Y-808405D01*
X396093Y-807605D01*
X395693Y-807072D01*
X394993Y-806672D01*
X392293D01*
Y-814672D01*
X395593D01*
X396293Y-814139D01*
X396693Y-813339D01*
X396893Y-812405D01*
X396693Y-811472D01*
X396093Y-810672D01*
X395393Y-810405D01*
X392293D01*
G01X400093Y-814672D02*
X402593Y-806672D01*
X405093Y-814672D01*
G01X404193Y-811872D02*
X400993D01*
G01X408693Y-814672D02*
Y-806672D01*
X412493D01*
G01X411093Y-810539D02*
X408693D01*
G01X418593Y-806672D02*
X417793Y-806939D01*
X417193Y-807605D01*
X416793Y-808405D01*
X416493Y-809472D01*
X416393Y-810672D01*
X416493Y-811872D01*
X416793Y-812939D01*
X417193Y-813739D01*
X417793Y-814405D01*
X418593Y-814672D01*
X419393Y-814405D01*
X419993Y-813739D01*
X420393Y-812939D01*
X420693Y-811872D01*
X420793Y-810672D01*
X420693Y-809472D01*
X420393Y-808405D01*
X419993Y-807605D01*
X419393Y-806939D01*
X418593Y-806672D01*
G01X356693Y-787172D02*
Y-779172D01*
X360493D01*
G01X359093Y-783039D02*
X356693D01*
G01X366593Y-779172D02*
X365793Y-779439D01*
X365193Y-780105D01*
X364793Y-780905D01*
X364493Y-781972D01*
X364393Y-783172D01*
X364493Y-784372D01*
X364793Y-785439D01*
X365193Y-786239D01*
X365793Y-786905D01*
X366593Y-787172D01*
X367393Y-786905D01*
X367993Y-786239D01*
X368393Y-785439D01*
X368693Y-784372D01*
X368793Y-783172D01*
X368693Y-781972D01*
X368393Y-780905D01*
X367993Y-780105D01*
X367393Y-779439D01*
X366593Y-779172D01*
G01X374593D02*
Y-787172D01*
G01X372293Y-779172D02*
X376893D01*
G01X379593Y-789839D02*
X385593D01*
G01X388593Y-787172D02*
Y-779172D01*
X390993D01*
X391793Y-779572D01*
X392393Y-780505D01*
X392593Y-781572D01*
X392393Y-782639D01*
X391893Y-783439D01*
X390993Y-783839D01*
X388593D01*
G01X396393Y-787172D02*
Y-779172D01*
X398393D01*
X399193Y-779572D01*
X399793Y-780105D01*
X400293Y-780905D01*
X400693Y-781839D01*
X400793Y-783172D01*
X400693Y-784505D01*
X400293Y-785439D01*
X399793Y-786239D01*
X399193Y-786772D01*
X398393Y-787172D01*
X396393D01*
G01X407393Y-782905D02*
X407793Y-782505D01*
X408093Y-781839D01*
X408293Y-780905D01*
X408093Y-780105D01*
X407693Y-779572D01*
X406993Y-779172D01*
X404293D01*
Y-787172D01*
X407593D01*
X408293Y-786639D01*
X408693Y-785839D01*
X408893Y-784905D01*
X408693Y-783972D01*
X408093Y-783172D01*
X407393Y-782905D01*
X404293D01*
G01X411593Y-789839D02*
X417593D01*
G01X424793Y-779839D02*
X424193Y-779439D01*
X423493Y-779172D01*
X422693D01*
X421793Y-779572D01*
X421093Y-780239D01*
X420593Y-781039D01*
X420193Y-782372D01*
X420093Y-783572D01*
X420293Y-784772D01*
X420593Y-785572D01*
X421193Y-786372D01*
X421893Y-786905D01*
X422593Y-787172D01*
X423293D01*
X423993Y-786905D01*
X424593Y-786505D01*
X425093Y-785972D01*
G01X430593Y-787172D02*
X429793Y-787039D01*
X429093Y-786505D01*
X428493Y-785705D01*
X428093Y-784772D01*
X427893Y-783705D01*
Y-782639D01*
X428093Y-781572D01*
X428493Y-780639D01*
X429093Y-779839D01*
X429793Y-779305D01*
X430593Y-779172D01*
X431393Y-779305D01*
X432093Y-779839D01*
X432693Y-780639D01*
X433093Y-781572D01*
X433293Y-782639D01*
Y-783705D01*
X433093Y-784772D01*
X432693Y-785705D01*
X432093Y-786505D01*
X431393Y-787039D01*
X430593Y-787172D01*
G01X436293D02*
Y-779172D01*
X440893Y-787172D01*
Y-779172D01*
G01X444093D02*
X446593Y-787172D01*
X449093Y-779172D01*
G01X456593Y-787172D02*
X452593D01*
Y-779172D01*
X456593D01*
G01X454993Y-783039D02*
X452593D01*
G01X460593Y-787172D02*
Y-779172D01*
X463093D01*
X463893Y-779572D01*
X464393Y-780105D01*
X464593Y-781172D01*
X464393Y-782239D01*
X463793Y-782905D01*
X463093Y-783305D01*
X460593D01*
G01X463093D02*
X464593Y-787172D01*
G01X470593Y-779172D02*
Y-787172D01*
G01X468293Y-779172D02*
X472893D01*
G01X480593Y-787172D02*
X476593D01*
Y-779172D01*
X480593D01*
G01X478993Y-783039D02*
X476593D01*
G01X484593Y-787172D02*
Y-779172D01*
X487093D01*
X487893Y-779572D01*
X488393Y-780105D01*
X488593Y-781172D01*
X488393Y-782239D01*
X487793Y-782905D01*
X487093Y-783305D01*
X484593D01*
G01X487093D02*
X488593Y-787172D01*
G01X425093Y-840172D02*
Y-832172D01*
X423893Y-833772D01*
G01Y-840172D02*
X426293D01*
G01X431193Y-836839D02*
X431893Y-835905D01*
X432493Y-835372D01*
X433293Y-835105D01*
X433993Y-835372D01*
X434493Y-835905D01*
X434893Y-836705D01*
X434993Y-837639D01*
X434893Y-838439D01*
X434493Y-839239D01*
X433893Y-839905D01*
X433193Y-840172D01*
X432393Y-839905D01*
X431693Y-839106D01*
X431293Y-837905D01*
X431193Y-836572D01*
X431393Y-834839D01*
X431693Y-833905D01*
X432193Y-832972D01*
X432893Y-832305D01*
X433593Y-832172D01*
X434293Y-832439D01*
X434793Y-833105D01*
G01X441093Y-840439D02*
X440893Y-840305D01*
Y-840039D01*
X441093Y-839905D01*
X441293Y-840039D01*
Y-840305D01*
X441093Y-840439D01*
G01X447193Y-836839D02*
X447893Y-835905D01*
X448493Y-835372D01*
X449293Y-835105D01*
X449993Y-835372D01*
X450493Y-835905D01*
X450893Y-836705D01*
X450993Y-837639D01*
X450893Y-838439D01*
X450493Y-839239D01*
X449893Y-839905D01*
X449193Y-840172D01*
X448393Y-839905D01*
X447693Y-839106D01*
X447293Y-837905D01*
X447193Y-836572D01*
X447393Y-834839D01*
X447693Y-833905D01*
X448193Y-832972D01*
X448893Y-832305D01*
X449593Y-832172D01*
X450293Y-832439D01*
X450793Y-833105D01*
G01X470093Y-840172D02*
Y-832172D01*
X468893Y-833772D01*
G01Y-840172D02*
X471293D01*
G01X477893D02*
X478093Y-838439D01*
X478393Y-836972D01*
X478793Y-835639D01*
X479293Y-834172D01*
X480093Y-832172D01*
X476093D01*
G01X486093Y-840439D02*
X485893Y-840305D01*
Y-840039D01*
X486093Y-839905D01*
X486293Y-840039D01*
Y-840305D01*
X486093Y-840439D01*
G01X492193Y-833505D02*
X492793Y-832705D01*
X493493Y-832305D01*
X494293Y-832172D01*
X495293Y-832439D01*
X495993Y-833105D01*
X496193Y-833905D01*
X496093Y-834706D01*
X495693Y-835372D01*
X493693Y-836705D01*
X492793Y-837639D01*
X492193Y-838972D01*
X491993Y-840172D01*
X496193D01*
G01X490193Y-815172D02*
Y-807172D01*
X493993D01*
G01X492593Y-811039D02*
X490193D01*
G54D59*
X1046126Y100500D03*
X1061874D03*
X1100126Y107000D03*
X1115874D03*
G54D68*
X1226024Y174429D03*
Y399429D03*
G54D78*
G01X33780Y334724D02*
X35004Y333500D01*
X40000D01*
X42116Y331384D01*
X45384D01*
X47220Y333220D01*
X64220D01*
X71220Y340220D01*
X142000D01*
X151220Y331000D01*
X151925D01*
G01X843000Y360075D02*
Y362911D01*
X829649Y376262D01*
X772752D01*
X770736Y378278D01*
X737228D01*
X703610Y344660D01*
X602581D01*
X587451Y359790D01*
X36845D01*
X27000Y349945D01*
Y342555D01*
X30451Y339104D01*
X34396D01*
X37720Y335780D01*
X42724D01*
X43780Y334724D01*
G01X786500Y316700D02*
X784490Y318710D01*
X762946D01*
X758036Y313800D01*
X723600D01*
X718220Y319180D01*
X589843D01*
X578663Y330360D01*
X188319D01*
X176999Y319040D01*
X148153D01*
X137833Y329360D01*
X83919D01*
X71979Y317420D01*
X59779D01*
X51279Y308920D01*
X39584D01*
X33780Y314724D01*
G01X69745Y350042D02*
X54958D01*
X51280Y353720D01*
X37720D01*
X33780Y349780D01*
Y344724D01*
G01X48780Y339724D02*
X47724Y340780D01*
X42720D01*
X40436Y343064D01*
X37064D01*
X35384Y341384D01*
X31396D01*
X29280Y343500D01*
Y349000D01*
X37790Y357510D01*
X586506D01*
X601636Y342380D01*
X704555D01*
X738173Y375998D01*
X769791D01*
X771807Y373982D01*
X827138D01*
X840500Y360620D01*
Y337000D01*
X849525Y327975D01*
X903500D01*
G01X60600Y335500D02*
X48000D01*
X45000Y338500D01*
X40004D01*
X38780Y339724D01*
G01X151925Y335500D02*
X144925Y342500D01*
X67600D01*
X60600Y335500D01*
G01X779100Y326820D02*
X760420D01*
X754980Y321380D01*
X726764D01*
X720724Y327420D01*
X597242D01*
X586662Y338000D01*
X180982D01*
X170862Y327880D01*
X150119D01*
X140999Y337000D01*
X72499D01*
X61319Y325820D01*
X44876D01*
X43780Y324724D01*
G01X68403Y323700D02*
X47700D01*
X45000Y321000D01*
X42500D01*
X38780Y324720D01*
Y329724D01*
G01X161400Y323200D02*
X149481D01*
X139441Y333240D01*
X82040D01*
X70100Y321300D01*
X58100D01*
X51524Y314724D01*
X43780D01*
G01X179400Y326800D02*
X173520Y320920D01*
X148932D01*
X138612Y331240D01*
X83140D01*
X71200Y319300D01*
X59000D01*
X50500Y310800D01*
X40600D01*
X38780Y312620D01*
Y319724D01*
G01X63436Y353962D02*
X586829D01*
X600691Y340100D01*
X705500D01*
X738678Y373278D01*
X769286D01*
X770862Y371702D01*
X776448D01*
X777705Y370445D01*
Y370370D01*
X778575Y369500D01*
G01X151925Y346500D02*
X61500D01*
X61000Y346000D01*
X47500D01*
X45000Y348500D01*
X40004D01*
X38780Y349724D01*
G01X827075Y334000D02*
X824575Y331500D01*
X811000D01*
X807200Y327700D01*
X785599D01*
X782249Y324350D01*
X760609D01*
X755759Y319500D01*
X725985D01*
X719945Y325540D01*
X596463D01*
X585883Y336120D01*
X181761D01*
X171641Y326000D01*
X149340D01*
X140220Y335120D01*
X79823D01*
X68403Y323700D01*
G01X151925Y350500D02*
X151467Y350042D01*
X69745D01*
G01X178329Y227723D02*
Y232900D01*
G01X175481Y225183D02*
X176500Y226202D01*
Y231071D01*
X178329Y232900D01*
G01X181449Y223523D02*
X183394D01*
X185954Y226083D01*
G01X181479Y227723D02*
X184314D01*
X185954Y226083D01*
G01X155075Y331000D02*
X168831D01*
X171302Y333471D01*
G01X748075Y347700D02*
X745315Y344940D01*
X730940D01*
X716000Y330000D01*
X597888D01*
X584788Y343100D01*
X180931D01*
X171302Y333471D01*
G01X163247Y335500D02*
X155075D01*
G01X748075Y353200D02*
X745385Y350510D01*
X731811D01*
X713901Y332600D01*
X598514D01*
X585514Y345600D01*
X173347D01*
X163247Y335500D01*
G01X161400Y323200D02*
X171500D01*
X182540Y334240D01*
X585104D01*
X595684Y323660D01*
X719166D01*
X725206Y317620D01*
X756538D01*
X761388Y322470D01*
X783467D01*
X786817Y325820D01*
X796480D01*
X798400Y323900D01*
G01X179400Y326800D02*
X184840Y332240D01*
X579442D01*
X590622Y321060D01*
X718999D01*
X724379Y315680D01*
X757257D01*
X762167Y320590D01*
X784331D01*
X787621Y323880D01*
X793800D01*
G01X753000Y366500D02*
X751000Y368500D01*
X742506D01*
X709000Y334994D01*
X599346D01*
X586240Y348100D01*
X156675D01*
X155075Y346500D01*
G01Y350500D02*
X587065D01*
X599965Y337600D01*
X707920D01*
X741283Y370963D01*
X761723D01*
X766240Y366446D01*
G01X200197Y267204D02*
X203575Y270582D01*
Y297500D01*
G01X361000Y300425D02*
X360074D01*
X334259Y326240D01*
X215940D01*
X203575Y313875D01*
Y297500D01*
G01X212925Y305000D02*
Y300500D01*
G01Y309500D02*
Y305000D01*
G01Y315500D02*
Y309500D01*
G01X231693Y267204D02*
Y279264D01*
X232478Y280049D01*
X236502D01*
X237287Y280834D01*
Y281944D01*
X236502Y282729D01*
X232478D01*
X231693Y283514D01*
Y284624D01*
X232478Y285409D01*
X236502D01*
X237287Y286194D01*
Y287304D01*
X236502Y288089D01*
X232478D01*
X231693Y288874D01*
Y289984D01*
X232478Y290769D01*
X236502D01*
X237287Y291554D01*
Y292664D01*
X236502Y293449D01*
X232478D01*
X231693Y294234D01*
Y296694D01*
X233575Y298576D01*
Y300500D01*
G01X224575D02*
X223819Y299744D01*
Y267204D01*
G01X216075Y300500D02*
Y298160D01*
X215945Y298030D01*
Y267204D01*
G01X239567Y300425D02*
Y267204D01*
G01X230425Y305000D02*
Y300500D01*
G01Y309500D02*
Y305000D01*
G01X221425D02*
Y300500D01*
G01Y309500D02*
Y305000D01*
G01X230425Y313605D02*
Y309500D01*
G01X221425D02*
Y313000D01*
G01X223819Y455425D02*
Y450575D01*
G01X381299D02*
X381207Y450483D01*
X223911D01*
X223819Y450575D01*
G01Y458575D02*
Y477204D01*
G01X361000Y300425D02*
Y270527D01*
X357677Y267204D01*
G01X369925Y287357D02*
Y264575D01*
X373780Y260720D01*
X392220D01*
X392900Y261400D01*
X777713D01*
X783993Y267680D01*
X788955D01*
X798220Y276945D01*
Y284220D01*
X816500Y302500D01*
X829000D01*
X832720Y306220D01*
Y311000D01*
G01X381575Y300500D02*
Y298053D01*
X382360Y297268D01*
X386215D01*
X387000Y296483D01*
Y295373D01*
X386215Y294588D01*
X382360D01*
X381575Y293803D01*
Y292693D01*
X382360Y291908D01*
X386215D01*
X387000Y291123D01*
Y290013D01*
X386215Y289228D01*
X382360D01*
X381575Y288443D01*
Y287333D01*
X382360Y286548D01*
X386215D01*
X387000Y285763D01*
Y284653D01*
X386215Y283868D01*
X382360D01*
X381575Y283083D01*
Y274802D01*
X389173Y267204D01*
G01X373075Y300500D02*
Y275428D01*
X381299Y267204D01*
G01X390575Y300500D02*
X393000Y298075D01*
Y265000D01*
X391000Y263000D01*
X377629D01*
X373425Y267204D01*
G01X369925Y287357D02*
Y300500D01*
G01D02*
Y305000D01*
G01D02*
Y309500D01*
G01X387425Y305000D02*
Y300500D01*
G01Y309500D02*
Y305000D01*
G01X378425Y300500D02*
Y305000D01*
G01D02*
Y309500D01*
G01X382963Y316400D02*
X384599D01*
X387425Y313574D01*
Y309500D01*
G01X378479Y314111D02*
X380778D01*
X381139Y313750D01*
X382963D01*
G01X378425Y309500D02*
Y314057D01*
X378479Y314111D01*
G01X381299Y450575D02*
Y455425D01*
G01Y450575D02*
X412019D01*
G01X381299Y458575D02*
Y477204D01*
G01X397047Y300425D02*
Y267204D01*
G01X412019Y450575D02*
X409400Y447956D01*
Y435060D01*
X423060Y421400D01*
X528501D01*
X603301Y346600D01*
X702800D01*
X710500Y354300D01*
Y360000D01*
X708000Y362500D01*
X622500D01*
X605600Y379400D01*
Y448446D01*
G01X418582Y448000D02*
X418007Y447425D01*
X412019D01*
G01X421594Y438360D02*
Y444988D01*
X418582Y448000D01*
G01X412019Y450575D02*
X417019D01*
X423944Y457500D01*
G01X421594Y433500D02*
Y438360D01*
G01X426456Y451740D02*
X427094Y452378D01*
Y457500D01*
G01X697900Y352500D02*
X609800D01*
X513800Y448500D01*
X429696D01*
X426456Y451740D01*
G01X432019Y457575D02*
X427169D01*
X427094Y457500D01*
G01X531075Y300500D02*
Y267373D01*
X530906Y267204D01*
G01X538780D02*
Y293281D01*
X540075Y294576D01*
Y300500D01*
G01X830161Y311000D02*
Y307280D01*
X827940Y305059D01*
X815559D01*
X795940Y285440D01*
Y277890D01*
X788010Y269960D01*
X782874D01*
X776624Y263710D01*
X536290D01*
X535000Y265000D01*
Y295900D01*
G01X518575Y295500D02*
Y270621D01*
X515158Y267204D01*
G01X536925Y305500D02*
Y300500D01*
G01Y310500D02*
Y305500D01*
G01X535000Y295900D02*
Y298575D01*
X536925Y300500D01*
G01X527925Y305500D02*
Y310500D01*
G01Y300500D02*
Y305500D01*
G01X539619Y316400D02*
X533325D01*
X527925Y311000D01*
Y310500D01*
G01X538780Y450575D02*
Y455425D01*
G01X544500Y450575D02*
X538780D01*
G01Y458575D02*
Y477204D01*
G01X554528Y300425D02*
Y267204D01*
G01X546654D02*
Y277783D01*
X547439Y278568D01*
X549715D01*
X550500Y279353D01*
Y280463D01*
X549715Y281248D01*
X547439D01*
X546654Y282033D01*
Y283143D01*
X547439Y283928D01*
X549715D01*
X550500Y284713D01*
Y285823D01*
X549715Y286608D01*
X547439D01*
X546654Y287393D01*
Y292655D01*
X549075Y295076D01*
Y300500D01*
G01X545925Y310500D02*
Y305500D01*
G01D02*
Y300500D01*
G01X539619Y313400D02*
X541019D01*
X544019Y316400D01*
X545519D01*
X547019Y314900D01*
Y312700D01*
X545925Y311606D01*
Y310500D01*
G01X563000Y453240D02*
X566835D01*
X569500Y450575D01*
G01X544500D02*
X547584D01*
X547676Y450483D01*
X549408D01*
X549500Y450575D01*
G01X563000Y453240D02*
X554241D01*
X551484Y450483D01*
X549592D01*
X549500Y450575D01*
G01X589500Y452075D02*
X590776D01*
X594500Y448351D01*
Y380999D01*
X616899Y358600D01*
X704400D01*
G01X707750Y358750D02*
X705960Y360540D01*
X617618D01*
X597500Y380658D01*
Y450500D01*
X590500Y457500D01*
X578575D01*
G01X578984Y438000D02*
Y445079D01*
X576063Y448000D01*
G01X579075Y433500D02*
X578984Y433591D01*
Y438000D01*
G01X576063Y448000D02*
X575488Y447425D01*
X569500D01*
G01Y450575D02*
X574500D01*
X575425Y451500D01*
Y457500D01*
G01X589500Y452075D02*
X584272D01*
X583937Y451740D01*
G01X605600Y448446D02*
Y451300D01*
X609725Y455425D01*
X696261D01*
G01X850750Y250750D02*
X847260Y247260D01*
Y190060D01*
X840300Y183100D01*
X818100D01*
X798500Y163500D01*
Y79800D01*
X785100Y66400D01*
Y25800D01*
X779550Y20250D01*
X660749D01*
X647999Y33000D01*
G01X676075Y299600D02*
Y270640D01*
X672639Y267204D01*
G01X685406Y305500D02*
Y310500D01*
G01Y300500D02*
Y305500D01*
G01X680400Y310500D02*
X685406D01*
G01X700040Y258960D02*
X783660D01*
X793100Y268400D01*
X794300D01*
X798500Y272600D01*
G01X696261Y267204D02*
Y293281D01*
X697556Y294576D01*
Y300500D01*
G01X712009Y300425D02*
Y267204D01*
G01X704135D02*
Y277269D01*
X704920Y278054D01*
X708944D01*
X709729Y278839D01*
Y279949D01*
X708944Y280734D01*
X704920D01*
X704135Y281519D01*
Y282629D01*
X704920Y283414D01*
X708944D01*
X709729Y284199D01*
Y285309D01*
X708944Y286094D01*
X704920D01*
X704135Y286879D01*
Y287989D01*
X704920Y288774D01*
X708944D01*
X709729Y289559D01*
Y290669D01*
X708944Y291454D01*
X704920D01*
X704135Y292239D01*
Y296635D01*
X706556Y299056D01*
Y300500D01*
G01X688556D02*
X689500Y299556D01*
Y291036D01*
X688556Y290092D01*
Y267373D01*
X688387Y267204D01*
G01X694406Y310500D02*
Y305500D01*
G01D02*
Y300500D01*
G01D02*
Y295500D01*
G01X703406Y305500D02*
Y300500D01*
G01Y310500D02*
Y305500D01*
G01X697100Y313400D02*
X700506D01*
X703406Y310500D01*
G01X696261Y450575D02*
Y455425D01*
G01Y458575D02*
Y477204D01*
G01X735075Y328500D02*
Y326000D01*
G01Y328500D02*
X737765Y331190D01*
X745469D01*
X748075Y328584D01*
G01X735075Y338500D02*
Y336000D01*
G01X731925Y338500D02*
Y336000D01*
G01Y328500D02*
Y326075D01*
X732000Y326000D01*
G01X744925Y338500D02*
X735075D01*
G01X753500Y326000D02*
X756500Y329000D01*
Y334342D01*
X758642Y336484D01*
X760280D01*
G01X753500Y326000D02*
X752000Y324500D01*
X748075D01*
G01Y328584D02*
Y328500D01*
G01X760280Y339043D02*
X757944D01*
X754250Y335349D01*
Y334759D01*
X748075Y328584D01*
G01Y334500D02*
Y338500D01*
G01X754000Y353500D02*
X756499D01*
X757397Y354398D01*
X760280D01*
G01Y356957D02*
X754000D01*
G01X748075Y342500D02*
X750831D01*
X752492Y344161D01*
X753550D01*
G01D02*
X760280D01*
G01Y351839D02*
X763320D01*
X764000Y352519D01*
Y360500D01*
X759000Y365500D01*
G01X775425Y369500D02*
Y364500D01*
G01D02*
Y358575D01*
X779602Y354398D01*
X782720D01*
G01X760280Y346720D02*
X749055D01*
X748075Y347700D01*
G01X760280Y349280D02*
X751995D01*
X748075Y353200D01*
G01X753000Y366500D02*
X755000Y368500D01*
X760500D01*
X769000Y360000D01*
Y343000D01*
X772957Y339043D01*
X782720D01*
G01X766240Y366446D02*
X771606Y361080D01*
Y344394D01*
X774398Y341602D01*
X782720D01*
G01X748075Y338500D02*
X753020D01*
G01D02*
X753871D01*
X756973Y341602D01*
X760280D01*
G01X879038Y271576D02*
X853580Y246118D01*
Y190738D01*
X841944Y179102D01*
X819944D01*
X802300Y161458D01*
Y121700D01*
X810000Y114000D01*
X817151D01*
X822559Y119408D01*
G01X812559D02*
X811933D01*
X804180Y127161D01*
Y160679D01*
X820723Y177222D01*
X843121D01*
X855460Y189561D01*
Y244643D01*
X883437Y272620D01*
X890676D01*
G01X871049Y266946D02*
X851700Y247597D01*
Y191699D01*
X841001Y181000D01*
X819183D01*
X800420Y162237D01*
Y119580D01*
X809000Y111000D01*
X833000D01*
X837000Y115000D01*
Y121500D01*
X833120Y125380D01*
X816587D01*
X812559Y129408D01*
G01X835280Y311000D02*
Y305500D01*
X829780Y300000D01*
X817500D01*
X800800Y283300D01*
Y274900D01*
X798500Y272600D01*
G01X797425Y330000D02*
X797101D01*
X788058Y339043D01*
X782720D01*
G01Y341602D02*
X788898D01*
X795500Y335000D01*
X797425D01*
G01X778575Y369500D02*
X781500Y366575D01*
Y362700D01*
G01X782720Y351839D02*
X790730D01*
G01D02*
X797264D01*
X797425Y352000D01*
G01Y357000D02*
X795001D01*
X794001Y358000D01*
X792000D01*
G01X808425Y357000D02*
X805985Y359440D01*
X799564D01*
X797425Y357301D01*
Y357000D01*
G01X792000Y358000D02*
X788499D01*
X787456Y356957D01*
X782720D01*
G01X808425Y362000D02*
X805985Y364440D01*
X799564D01*
X797425Y362301D01*
Y362000D01*
G01D02*
X791000D01*
G01D02*
X788000D01*
X785516Y359516D01*
X782720D01*
G01Y344161D02*
X790319D01*
X791563Y342917D01*
G01D02*
X793480Y341000D01*
X797425D01*
G01X808425D02*
X804501D01*
X802001Y343500D01*
X794500D01*
X791280Y346720D01*
X782720D01*
G01Y349280D02*
X792100D01*
X794880Y346500D01*
X797425D01*
G01X808425Y344000D02*
Y346500D01*
X805735Y349190D01*
X800115D01*
X797425Y346500D01*
G01X1082833Y602542D02*
X788080D01*
X787400Y603222D01*
Y611862D01*
X788080Y612542D01*
X1082833D01*
G01X832559Y119408D02*
Y119410D01*
X828469Y123500D01*
X810500D01*
X806200Y127800D01*
Y159700D01*
X821842Y175342D01*
X843900D01*
X857340Y188782D01*
Y242968D01*
X884558Y270186D01*
X901261D01*
X903939Y272864D01*
G01X832559Y129408D02*
X836068Y132589D01*
X839414Y136666D01*
X841319Y141990D01*
Y149581D01*
X871800Y180062D01*
Y240429D01*
X890371Y259000D01*
X931545D01*
X945201Y272656D01*
G01X937676Y268356D02*
X935827Y266507D01*
X934921D01*
X933267Y268161D01*
X932361D01*
X931718Y267518D01*
Y266612D01*
X933372Y264958D01*
Y264052D01*
X930600Y261280D01*
X889426D01*
X869500Y241354D01*
Y182189D01*
X837889Y150578D01*
Y143045D01*
X836582Y137827D01*
X835541Y136348D01*
X822559Y129408D01*
G01X832559Y139408D02*
X827500Y144467D01*
Y153500D01*
X837000Y163000D01*
X846500D01*
X867000Y183500D01*
Y242079D01*
X888481Y263560D01*
X920660D01*
X930086Y272986D01*
G01X812559Y149408D02*
Y159059D01*
X825000Y171500D01*
X846625D01*
X861100Y185975D01*
Y239404D01*
X887536Y265840D01*
X913915D01*
X920899Y272824D01*
G01X822559Y139408D02*
X817651Y134500D01*
X809499D01*
X808200Y135799D01*
Y158200D01*
X823462Y173462D01*
X845089D01*
X859220Y187593D01*
Y241349D01*
X885871Y268000D01*
X909575D01*
X913078Y271503D01*
G01X832559Y149408D02*
X842075Y158924D01*
G01X843000Y167000D02*
X837500D01*
X822559Y152059D01*
Y149408D01*
G01X826000Y276075D02*
X826924D01*
X828500Y274499D01*
Y268575D01*
X826000Y266075D01*
G01X827602Y283500D02*
Y281002D01*
X826000Y279400D01*
Y276075D01*
G01X831000D02*
X831924D01*
X833500Y274499D01*
Y268575D01*
G01X830161Y288000D02*
Y280838D01*
X831000Y279999D01*
Y276075D01*
G01X833500Y268575D02*
X831000Y266075D01*
G01X821000Y270525D02*
Y272925D01*
G01X816000Y270525D02*
Y272925D01*
G01X815500Y281500D02*
Y280499D01*
X816000Y279999D01*
Y276075D01*
G01X823206Y281207D02*
X821000Y279001D01*
Y276075D01*
G01X827602Y288000D02*
Y283500D01*
G01X832720Y288000D02*
Y282355D01*
X833500Y281575D01*
Y281000D01*
G01D02*
X836000Y278500D01*
Y276075D01*
G01X822484Y288000D02*
Y284984D01*
X819000Y281500D01*
X815500D01*
G01X825043Y288000D02*
Y283044D01*
X823206Y281207D01*
G01X811000Y286000D02*
X819941Y294941D01*
X843940D01*
X845516Y293365D01*
Y288000D01*
G01X806500Y282575D02*
X807575D01*
X811000Y286000D01*
G01X806500Y282575D02*
Y285500D01*
G01X814500Y293000D02*
X819000Y297500D01*
X845000D01*
X848075Y294425D01*
Y288000D01*
G01X819925Y311000D02*
Y313575D01*
X815000Y318500D01*
G01D02*
X811500Y322000D01*
Y323425D01*
G01X815500D02*
X819500D01*
G01X822484Y311000D02*
Y315516D01*
X819500Y318500D01*
G01D02*
Y323425D01*
G01X827500D02*
X823500D01*
G01X825043Y311000D02*
Y316043D01*
X827500Y318500D01*
G01D02*
Y323425D01*
G01X831059Y342260D02*
Y339441D01*
X833500Y337000D01*
G01X808425Y341000D02*
Y334000D01*
G01X823925D02*
X820180D01*
X819500Y334680D01*
Y336500D01*
G01D02*
X820500Y337500D01*
X827820D01*
X828500Y338180D01*
Y342260D01*
G01X827075Y334000D02*
X829500D01*
X831000Y332500D01*
X834425D01*
G01D02*
Y328000D01*
G01D02*
Y323500D01*
G01X827602Y311000D02*
Y314102D01*
X831750Y318250D01*
G01X868000Y271500D02*
X871000Y274500D01*
Y277682D01*
X859000Y289682D01*
Y308400D01*
X847400Y320000D01*
X841400D01*
X839650Y318250D01*
X831750D01*
G01X821500Y354925D02*
X827000D01*
G01D02*
Y352500D01*
G01D02*
Y350799D01*
X825941Y349740D01*
G01X821500Y358075D02*
Y362001D01*
X824499Y365000D01*
X831500D01*
X838220Y358280D01*
Y336221D01*
X837575Y335576D01*
Y332500D01*
G01X863600Y208900D02*
Y183325D01*
X847275Y167000D01*
X843000D01*
G01X841000Y276075D02*
X841925D01*
X843500Y274500D01*
Y268575D01*
G01X835280Y288000D02*
Y283535D01*
X839000Y279815D01*
Y278075D01*
X841000Y276075D01*
G01X843500Y268575D02*
X841000Y266075D01*
G01X836000Y276075D02*
X836424D01*
X838500Y273999D01*
Y268575D01*
X836000Y266075D01*
G01X856000Y276075D02*
X856301D01*
X858440Y273936D01*
Y268515D01*
X856000Y266075D01*
G01X849500Y281500D02*
X851000D01*
X856000Y276500D01*
Y276075D01*
G01X851000D02*
X851924D01*
X853500Y274499D01*
Y268575D01*
G01X840398Y288000D02*
Y284761D01*
X846659Y278500D01*
X848575D01*
X851000Y276075D01*
G01X853500Y268575D02*
X851000Y266075D01*
G01X846000D02*
X848440Y268515D01*
Y273936D01*
X847011Y275365D01*
X846710D01*
X846000Y276075D01*
G01X841409Y280566D02*
X845900Y276075D01*
X846000D01*
G01X850750Y250750D02*
X873500Y273500D01*
Y277841D01*
X861600Y289741D01*
Y304600D01*
G01X842957Y288000D02*
Y284861D01*
X846318Y281500D01*
X849500D01*
G01X837839Y288000D02*
Y284136D01*
X841409Y280566D01*
G01X877500Y277925D02*
X876075D01*
X864500Y289500D01*
Y309100D01*
X841100Y332500D01*
X837575D01*
G01X845516Y311000D02*
Y305984D01*
X848000Y303500D01*
X853000D01*
G01X836500Y302500D02*
X837839Y303839D01*
Y311000D01*
G01X842957D02*
Y305043D01*
X845000Y303000D01*
G01X848500Y335800D02*
Y340177D01*
G01X852000Y334075D02*
X850225D01*
X848500Y335800D01*
G01X852240Y340177D02*
Y338260D01*
X859200Y331300D01*
X884980D01*
X899180Y345500D01*
X908937D01*
G01X842600Y317600D02*
X840398Y315398D01*
Y311000D01*
G01X864500Y352925D02*
X860000Y348425D01*
Y348000D01*
G01D02*
X865000Y343000D01*
Y338900D01*
G01X843000Y356925D02*
Y355185D01*
X843843Y354342D01*
G01X847500Y356925D02*
X843000D01*
G01X843843Y354342D02*
X844760Y353425D01*
Y349823D01*
G01X864500Y358500D02*
Y356075D01*
G01X888000Y277925D02*
X884000D01*
G01X888000D02*
X884575Y274500D01*
X881962D01*
X879038Y271576D01*
G01X898500Y277925D02*
X893195Y272620D01*
X890676D01*
G01X871049Y266946D02*
X877500Y273397D01*
Y277925D01*
G01X870000Y297075D02*
X867560Y299515D01*
Y307936D01*
X869699Y310075D01*
X870000D01*
G01X867000Y291260D02*
X890063D01*
G01X880000Y297075D02*
X877500Y299575D01*
Y307876D01*
X879699Y310075D01*
X880000D01*
G01X875000Y297075D02*
X872500Y299575D01*
Y301906D01*
G01D02*
Y307575D01*
X875000Y310075D01*
G01X888000Y283475D02*
Y281075D01*
G01X870000Y310075D02*
Y312788D01*
G01D02*
Y318100D01*
G01X880000Y310075D02*
Y312855D01*
G01D02*
Y318100D01*
G01X875000Y310075D02*
Y318100D01*
G01X874000Y352925D02*
X878000D01*
G01X875000Y338900D02*
Y347273D01*
G01D02*
Y350185D01*
X874000Y351185D01*
Y352925D01*
G01X871000Y348000D02*
X870000Y347000D01*
Y338900D01*
G01X869000Y352925D02*
X871000Y350925D01*
Y348000D01*
G01X869000Y360500D02*
Y356075D01*
G01X903939Y272864D02*
X909000Y277925D01*
G01D02*
X905000D01*
G01X926000D02*
X920899Y272824D01*
G01X898500Y277925D02*
X894500D01*
G01X913078Y271503D02*
X919500Y277925D01*
G01D02*
X915500D01*
G01X909000Y283475D02*
Y281075D01*
G01X920000Y320135D02*
Y312000D01*
X936000Y296000D01*
Y287499D01*
X933000Y284499D01*
Y281075D01*
G01X909500Y294425D02*
Y294255D01*
X915143Y288612D01*
G01D02*
X919500Y284255D01*
Y281075D01*
G01X914500Y297575D02*
X909500D01*
G01X911059Y309260D02*
Y307352D01*
X914500Y303911D01*
G01D02*
Y297575D01*
G01X908500Y309260D02*
Y305500D01*
X905819Y302819D01*
G01D02*
X904500Y301500D01*
Y297575D01*
G01X898500Y281075D02*
Y285686D01*
G01D02*
Y294437D01*
X897937Y295000D01*
G01X920000Y341177D02*
Y320135D01*
G01X905941Y316740D02*
Y320366D01*
G01X908000Y322425D02*
X903500D01*
G01X905941Y320366D02*
X908000Y322425D01*
G01X901063Y341760D02*
X903500Y339323D01*
Y327975D01*
G01D02*
Y325575D01*
G01X909500Y335575D02*
X908937Y336138D01*
Y345500D01*
G01X915500Y357925D02*
Y355760D01*
X916260Y355000D01*
G01D02*
Y350823D01*
G01X910992Y361075D02*
X915500D01*
G01D02*
X920000D01*
G01X908937Y345500D02*
X923740D01*
G01D02*
Y341177D01*
G01X930086Y272986D02*
X933000Y275900D01*
Y277925D01*
G01D02*
X930500Y280425D01*
Y285425D01*
X933000Y287925D01*
G01X947000Y277925D02*
Y274455D01*
X945201Y272656D01*
G01X947000Y277925D02*
X946925D01*
X944720Y280130D01*
Y285645D01*
X947000Y287925D01*
G01X940000Y277925D02*
Y270680D01*
X937676Y268356D01*
G01X940000Y277925D02*
X937500Y280425D01*
Y285425D01*
X940000Y287925D01*
G01X937621Y310885D02*
X932500Y305764D01*
Y305385D01*
G01D02*
X936310D01*
X937425Y306500D01*
G01X940575Y304000D02*
Y306500D01*
G01X947000Y296925D02*
X950350Y293575D01*
Y290350D01*
X947925Y287925D01*
X947000D01*
G01X940000Y296925D02*
X943130Y293795D01*
Y291055D01*
X940000Y287925D01*
G01X947000Y281075D02*
Y281500D01*
X952000Y286500D01*
G01D02*
X952910Y287410D01*
Y344589D01*
X949614Y347885D01*
X941271D01*
G01X940000Y283800D02*
Y281075D01*
G01X937621Y315385D02*
Y310885D01*
G01X935916Y322596D02*
Y317090D01*
X937621Y315385D01*
G01X938476Y322596D02*
Y317755D01*
X940771Y315460D01*
Y315385D01*
G01X943171D02*
X940771D01*
G01X941035Y322596D02*
Y319965D01*
X942000Y319000D01*
X945500D01*
G01X938121Y347885D02*
Y352385D01*
G01X935916Y340174D02*
Y345680D01*
X938121Y347885D01*
G01Y352385D02*
X942546Y356810D01*
Y357925D01*
G01D02*
X938000D01*
G01X935516Y361075D02*
X938000D01*
G01X933357Y340174D02*
Y344843D01*
G01D02*
Y347649D01*
X933196Y347810D01*
G01X938476Y340174D02*
Y345015D01*
X941271Y347810D01*
Y347885D01*
G01X933196Y353360D02*
Y350960D01*
G01X1119000Y189500D02*
X1115855Y192645D01*
X1083203D01*
X1074448Y201400D01*
X1055400D01*
X1046000Y192000D01*
Y178000D01*
X1034500Y166500D01*
Y145000D01*
G01X1037000Y146300D02*
Y150800D01*
X1038500Y152300D01*
Y167841D01*
X1048500Y177841D01*
Y191499D01*
X1056521Y199520D01*
X1073421D01*
X1082177Y190764D01*
X1112436D01*
X1114500Y188700D01*
G01X1077500Y100563D02*
X1061937D01*
X1061874Y100500D01*
G01X1063500Y111500D02*
Y108900D01*
X1061874Y107274D01*
Y100500D01*
G01X1043500Y111500D02*
Y108200D01*
X1046126Y105574D01*
Y100500D01*
G01X1057240Y111500D02*
X1063500D01*
G01X1049575Y129000D02*
X1056865Y136290D01*
X1062209D01*
X1063075Y135424D01*
Y134000D01*
G01X1070715Y146500D02*
X1067000Y142785D01*
Y133000D01*
X1064500Y130500D01*
X1063075D01*
G01D02*
Y130074D01*
X1061211Y128210D01*
X1052285D01*
X1049575Y125500D01*
G01X1063500Y117500D02*
X1066840D01*
X1069340Y120000D01*
X1088600D01*
X1101100Y132500D01*
X1108300D01*
X1111800Y136000D01*
X1121500D01*
X1123500Y138000D01*
Y148677D01*
X1113937Y158240D01*
G01X1063500Y117500D02*
X1052500D01*
X1049760Y114760D01*
Y111500D01*
G01D02*
X1043500D01*
G01X1045075Y151000D02*
X1049356Y146719D01*
Y143900D01*
G01X1070000Y185925D02*
X1067625D01*
X1045075Y163375D01*
Y151000D01*
G01X1049575Y137500D02*
Y139071D01*
X1047159Y141487D01*
G01X1077000Y181425D02*
X1070125D01*
X1051796Y163096D01*
Y147204D01*
X1052620Y146380D01*
Y138804D01*
X1051316Y137500D01*
X1049575D01*
G01X1054500Y148500D02*
Y137525D01*
X1050575Y133600D01*
X1049575D01*
G01X1063075Y134000D02*
X1063500D01*
X1064500Y135000D01*
Y152000D01*
X1060500Y156000D01*
Y164500D01*
G01X1057500Y155877D02*
X1060575Y152802D01*
Y142000D01*
G01X1082000Y143600D02*
X1079100Y146500D01*
X1070715D01*
G01X1067500Y159575D02*
X1063739D01*
X1063500Y159814D01*
G01X1084401Y159260D02*
X1071980D01*
X1071665Y159575D01*
X1067500D01*
G01X1070000Y185925D02*
X1073500D01*
G01X1132000Y180575D02*
X1116165D01*
X1107940Y188800D01*
X1081200D01*
X1073860Y196140D01*
X1058300D01*
X1053830Y191670D01*
G01X1087000Y100000D02*
X1086437Y100563D01*
X1077500D01*
G01X1095500Y117075D02*
X1077500D01*
G01X1110500Y117260D02*
X1098760D01*
X1098575Y117075D01*
X1095500D01*
G01X1085300Y114016D02*
X1077591D01*
X1077500Y113925D01*
G01X1100126Y107000D02*
X1094336D01*
X1094236Y106900D01*
X1092416D01*
X1085300Y114016D01*
G01X1077500Y113925D02*
X1077409Y114016D01*
X1075676D01*
X1075660Y114000D01*
X1073575D01*
G01D02*
X1073483Y113908D01*
Y112176D01*
X1073760Y111899D01*
Y108437D01*
G01X1091240Y135000D02*
Y140540D01*
X1091740Y141040D01*
Y149063D01*
G01X1091240Y135000D02*
X1099223Y142983D01*
X1104408D01*
X1104500Y143075D01*
G01X1088000Y156937D02*
X1098500D01*
G01D02*
X1098958D01*
X1108821Y166800D01*
G01X1088000Y156937D02*
X1085677Y159260D01*
X1084401D01*
G01X1103575Y183500D02*
Y185324D01*
X1101999Y186900D01*
X1075899D01*
X1074924Y185925D01*
X1073500D01*
G01X1077000Y181425D02*
X1082500D01*
G01D02*
X1089075D01*
X1093500Y177000D01*
X1102499D01*
X1103575Y178076D01*
Y180000D01*
G01X1091075Y171000D02*
Y174500D01*
G01Y171000D02*
X1095500D01*
X1096000Y170500D01*
G01D02*
X1098000Y168500D01*
X1100425D01*
G01X1091075Y164000D02*
Y167500D01*
G01X1100425Y165000D02*
X1096000D01*
G01D02*
X1093500Y167500D01*
X1091075D01*
G01X1076800Y406925D02*
X1074316D01*
G01X1110500Y117260D02*
Y111000D01*
X1114500Y107000D01*
X1115874D01*
G01X1141500Y114525D02*
X1141165D01*
X1122998Y107000D01*
X1115874D01*
G01X1114000Y145075D02*
X1110000D01*
G01X1114000D02*
X1120663D01*
X1121238Y144500D01*
G01X1114000Y141925D02*
X1115425Y140500D01*
Y138925D01*
G01X1106063Y154500D02*
X1102000Y150437D01*
Y148000D01*
G01D02*
X1104500Y145500D01*
Y143075D01*
G01X1119000Y189500D02*
X1122077Y192577D01*
X1138535D01*
X1140575Y194617D01*
Y196500D01*
G01X1103575Y183500D02*
X1108500D01*
X1118000Y174000D01*
Y167000D01*
X1113800Y162800D01*
X1112049D01*
X1111100Y163749D01*
G01X1123500Y187000D02*
X1124777Y188277D01*
X1141277D01*
X1155500Y202500D01*
Y206260D01*
G01X1103575Y168500D02*
Y171076D01*
X1106999Y174500D01*
X1110487D01*
X1113368Y171619D01*
G01X1103575Y165000D02*
X1108075Y169500D01*
X1109000D01*
X1109500Y170000D01*
X1110800D01*
G01X1103575Y180000D02*
X1108500D01*
X1116000Y172500D01*
Y168590D01*
X1113129Y165719D01*
G01X1148000Y206260D02*
Y198500D01*
X1140177Y190677D01*
X1123677D01*
X1120000Y187000D01*
X1116200D01*
X1114500Y188700D01*
G01X1144563Y138000D02*
Y116565D01*
X1142523Y114525D01*
X1141500D01*
G01D02*
Y114425D01*
G01X1134571Y149734D02*
Y145143D01*
X1135980Y143734D01*
X1137720D01*
G01X1131476Y169294D02*
Y154433D01*
X1134571Y151338D01*
Y149734D01*
G01X1152437Y141740D02*
Y145389D01*
X1150425Y147401D01*
G01D02*
Y154000D01*
G01X1140870Y143734D02*
X1142611D01*
X1144019Y145142D01*
Y149734D01*
G01D02*
X1145288D01*
X1149554Y154000D01*
X1150425D01*
G01X1132000Y177425D02*
X1146335D01*
X1146760Y177000D01*
G01D02*
Y171395D01*
G01X1132000Y177425D02*
X1131476Y176901D01*
Y169294D01*
G01X1140500Y206260D02*
Y200575D01*
X1140575Y200500D01*
G01D02*
Y196500D01*
G01X1270000Y290000D02*
X1268100Y291900D01*
X1250995D01*
X1246024Y286929D01*
G01X1271500Y282000D02*
X1266571Y286929D01*
X1256024D01*
G54D69*
G01X742000Y341500D02*
X743925D01*
X744925Y342500D01*
G01X1158200Y137700D02*
X1158744Y138244D01*
Y159756D01*
X1152781Y165719D01*
M02*
